FILE_TYPE = MACRO_DRAWING;
SET COLOR_WIRE YELLOW;
SET COLOR_PROP MONO;
SET COLOR_DOT WHITE;
SET COLOR_ARC YELLOW;
SET COLOR_BODY GREEN;
SET COLOR_NOTE MONO;
SET PROP_DISPLAY VALUE;
SET PAGE_NUMBER P268;
FORCEADD OFFPAGE..1
(-8200 3900);
FORCEPROP 2 LAST $XR2 255 
J 0
(-8692 3900);
DISPLAY 0.638298 (-8692 3900);
PAINT MONO (-8692 3900);
FORCEPROP 2 LAST $XR1 146 
J 0
(-8572 3900);
DISPLAY 0.638298 (-8572 3900);
PAINT MONO (-8572 3900);
FORCEPROP 2 LAST $XR0 111 
J 0
(-8452 3900);
DISPLAY 0.638298 (-8452 3900);
PAINT MONO (-8452 3900);
FORCEPROP 2 LAST PATH I1
J 0
(-8450 3950);
DISPLAY 1.021277 (-8450 3950);
PAINT ORANGE (-8450 3950);
DISPLAY INVISIBLE (-8450 3950);
FORCEPROP 2 LAST CDS_LIB mstr_standard
J 0
(-8200 3900);
PAINT ORANGE (-8200 3900);
DISPLAY INVISIBLE (-8200 3900);
FORCEPROP 1 LAST OFFPAGE TRUE
J 0
(-7875 3775);
DISPLAY 1.404255 (-7875 3775);
PAINT GREEN (-7875 3775);
DISPLAY INVISIBLE (-7875 3775);
FORCEPROP 1 LAST COMMENT_BODY TRUE
J 0
(-8075 3800);
DISPLAY 1.404255 (-8075 3800);
PAINT PEACH (-8075 3800);
DISPLAY INVISIBLE (-8075 3800);
FORCEADD GND..1
(-6700 3975);
FORCEPROP 3 LASTPIN (-6700 4025) SIG_NAME GND\g
J 0
(-6690 4035);
DISPLAY 0.659574 (-6690 4035);
PAINT MONO (-6690 4035);
DISPLAY INVISIBLE (-6690 4035);
FORCEPROP 1 LAST PATH I10
J 0
(-6625 3975);
DISPLAY 0.872340 (-6625 3975);
PAINT AQUA (-6625 3975);
DISPLAY INVISIBLE (-6625 3975);
FORCEPROP 1 LAST SIZE 1B
J 0
(-6625 3925);
DISPLAY 1.170213 (-6625 3925);
PAINT AQUA (-6625 3925);
DISPLAY INVISIBLE (-6625 3925);
FORCEPROP 2 LAST CDS_LIB mstr_symbols
J 0
(-6700 3975);
PAINT ORANGE (-6700 3975);
DISPLAY INVISIBLE (-6700 3975);
FORCEPROP 1 LAST VOLTAGE 0.0V
J 0
(-6745 3932);
DISPLAY 0.340426 (-6745 3932);
PAINT SKYBLUE (-6745 3932);
DISPLAY INVISIBLE (-6745 3932);
FORCEPROP 1 LAST BODY_TYPE PLUMBING
J 0
(-6745 3932);
DISPLAY 0.340426 (-6745 3932);
PAINT GREEN (-6745 3932);
DISPLAY INVISIBLE (-6745 3932);
FORCEPROP 1 LAST HDL_POWER GND
J 0
(-6700 4125);
DISPLAY 1.170213 (-6700 4125);
PAINT GREEN (-6700 4125);
DISPLAY INVISIBLE (-6700 4125);
FORCEADD P3V3_STBY..1
(-6700 4350);
FORCEPROP 3 LASTPIN (-6700 4300) SIG_NAME P3V3_STBY\g
J 0
(-6690 4310);
DISPLAY 0.659574 (-6690 4310);
PAINT MONO (-6690 4310);
DISPLAY INVISIBLE (-6690 4310);
FORCEPROP 1 LAST PATH I11
J 0
(-6655 4352);
DISPLAY 0.340426 (-6655 4352);
PAINT GREEN (-6655 4352);
DISPLAY INVISIBLE (-6655 4352);
FORCEPROP 1 LAST VOLTAGE 3.3V
J 0
(-6745 4307);
DISPLAY 0.340426 (-6745 4307);
PAINT SKYBLUE (-6745 4307);
DISPLAY INVISIBLE (-6745 4307);
FORCEPROP 1 LAST SIZE 1B
J 0
(-6655 4372);
DISPLAY 0.340426 (-6655 4372);
PAINT GREEN (-6655 4372);
DISPLAY INVISIBLE (-6655 4372);
FORCEPROP 2 LAST CDS_LIB mstr_symbols
J 0
(-6700 4350);
PAINT ORANGE (-6700 4350);
DISPLAY INVISIBLE (-6700 4350);
FORCEPROP 1 LAST BODY_TYPE PLUMBING
J 0
(-6745 4307);
DISPLAY 0.340426 (-6745 4307);
PAINT GREEN (-6745 4307);
DISPLAY INVISIBLE (-6745 4307);
FORCEPROP 1 LAST HDL_POWER P3V3_STBY
J 0
(-7000 4225);
DISPLAY 0.872340 (-7000 4225);
PAINT ORANGE (-7000 4225);
DISPLAY INVISIBLE (-7000 4225);
FORCEADD TTL1G07_A..1
(-6300 3100);
FORCEPROP 1 LAST LOCATION U25W15
J 0
(-6400 3250);
DISPLAY 0.617021 (-6400 3250);
PAINT AQUA (-6400 3250);
FORCEPROP 1 LAST PART_NUMBER C88419-001
J 0
(-6350 2965);
DISPLAY 0.617021 (-6350 2965);
PAINT BLUE (-6350 2965);
FORCEPROP 2 LASTPIN (-6150 3100) $PN 4
J 0
(-6140 3110);
DISPLAY 0.617021 (-6140 3110);
PAINT ORANGE (-6140 3110);
FORCEPROP 1 LAST VALUE 74LVC1G07
J 1
(-6300 3200);
DISPLAY 0.617021 (-6300 3200);
PAINT SKYBLUE (-6300 3200);
FORCEPROP 2 LASTPIN (-6400 3100) $PN 2
J 2
(-6410 3110);
DISPLAY 0.617021 (-6410 3110);
PAINT ORANGE (-6410 3110);
FORCEPROP 1 LAST POWER_GROUP VCC=P3V3_STBY;GND=GND
J 1
(-6350 2910);
DISPLAY 0.617021 (-6350 2910);
PAINT ORANGE (-6350 2910);
FORCEPROP 1 LAST MATERIAL IC
J 0
(-6200 3250);
DISPLAY 0.617021 (-6200 3250);
PAINT SKYBLUE (-6200 3250);
FORCEPROP 1 LAST PATH I12
J 0
(-6250 3150);
DISPLAY 0.978723 (-6250 3150);
PAINT WHITE (-6250 3150);
DISPLAY INVISIBLE (-6250 3150);
FORCEPROP 2 LAST CDS_LOCATION U25W15
J 0
(-6400 3250);
DISPLAY 0.617021 (-6400 3250);
PAINT AQUA (-6400 3250);
DISPLAY INVISIBLE (-6400 3250);
FORCEPROP 1 LAST PACK_TYPE SOP
J 0
(-6350 3350);
DISPLAY 0.978723 (-6350 3350);
PAINT SKYBLUE (-6350 3350);
DISPLAY INVISIBLE (-6350 3350);
FORCEPROP 0 LAST BOM_COST SM_THERM
J 0
(-6350 3500);
DISPLAY 1.021277 (-6350 3500);
PAINT ORANGE (-6350 3500);
DISPLAY INVISIBLE (-6350 3500);
FORCEPROP 2 LAST SEC_TYPE SOP
J 0
(-6350 3350);
DISPLAY 1.021277 (-6350 3350);
PAINT ORANGE (-6350 3350);
DISPLAY INVISIBLE (-6350 3350);
FORCEPROP 2 LAST SEC 1
J 0
(-6350 3350);
DISPLAY 0.680851 (-6350 3350);
PAINT MONO (-6350 3350);
DISPLAY INVISIBLE (-6350 3350);
FORCEPROP 0 LAST ROOM CPU_FANS
J 0
(-6350 3400);
DISPLAY 1.021277 (-6350 3400);
PAINT ORANGE (-6350 3400);
DISPLAY INVISIBLE (-6350 3400);
FORCEPROP 2 LAST CDS_LIB mstr_ttl
J 0
(-6300 3100);
PAINT ORANGE (-6300 3100);
DISPLAY INVISIBLE (-6300 3100);
FORCEPROP 0 LAST CDS_SEC 1
J 0
(-6275 3300);
DISPLAY INVISIBLE (-6275 3300);
FORCEADD TTL1G07_A..1
(-6300 3900);
FORCEPROP 1 LAST POWER_GROUP VCC=P3V3_STBY;GND=GND
J 1
(-6350 3710);
DISPLAY 0.617021 (-6350 3710);
PAINT ORANGE (-6350 3710);
FORCEPROP 1 LAST PART_NUMBER C88419-001
J 0
(-6350 3765);
DISPLAY 0.617021 (-6350 3765);
PAINT BLUE (-6350 3765);
FORCEPROP 2 LASTPIN (-6150 3900) $PN 4
J 0
(-6140 3910);
DISPLAY 0.617021 (-6140 3910);
PAINT ORANGE (-6140 3910);
FORCEPROP 1 LAST MATERIAL IC
J 0
(-6200 4050);
DISPLAY 0.617021 (-6200 4050);
PAINT SKYBLUE (-6200 4050);
FORCEPROP 2 LASTPIN (-6400 3900) $PN 2
J 2
(-6410 3910);
DISPLAY 0.617021 (-6410 3910);
PAINT ORANGE (-6410 3910);
FORCEPROP 1 LAST VALUE 74LVC1G07
J 1
(-6300 4000);
DISPLAY 0.617021 (-6300 4000);
PAINT SKYBLUE (-6300 4000);
FORCEPROP 1 LAST LOCATION U25W14
J 0
(-6400 4050);
DISPLAY 0.617021 (-6400 4050);
PAINT AQUA (-6400 4050);
FORCEPROP 1 LAST PATH I13
J 0
(-6250 3950);
DISPLAY 0.978723 (-6250 3950);
PAINT WHITE (-6250 3950);
DISPLAY INVISIBLE (-6250 3950);
FORCEPROP 2 LAST CDS_LOCATION U25W14
J 0
(-6400 4050);
DISPLAY 0.617021 (-6400 4050);
PAINT AQUA (-6400 4050);
DISPLAY INVISIBLE (-6400 4050);
FORCEPROP 1 LAST PACK_TYPE SOP
J 0
(-6350 4150);
DISPLAY 0.978723 (-6350 4150);
PAINT SKYBLUE (-6350 4150);
DISPLAY INVISIBLE (-6350 4150);
FORCEPROP 0 LAST BOM_COST SM_THERM
J 0
(-6350 4300);
DISPLAY 1.021277 (-6350 4300);
PAINT ORANGE (-6350 4300);
DISPLAY INVISIBLE (-6350 4300);
FORCEPROP 2 LAST SEC_TYPE SOP
J 0
(-6350 4150);
DISPLAY 1.021277 (-6350 4150);
PAINT ORANGE (-6350 4150);
DISPLAY INVISIBLE (-6350 4150);
FORCEPROP 2 LAST SEC 1
J 0
(-6350 4150);
DISPLAY 0.680851 (-6350 4150);
PAINT MONO (-6350 4150);
DISPLAY INVISIBLE (-6350 4150);
FORCEPROP 0 LAST ROOM CPU_FANS
J 0
(-6350 4200);
DISPLAY 1.021277 (-6350 4200);
PAINT ORANGE (-6350 4200);
DISPLAY INVISIBLE (-6350 4200);
FORCEPROP 2 LAST CDS_LIB mstr_ttl
J 0
(-6300 3900);
PAINT ORANGE (-6300 3900);
DISPLAY INVISIBLE (-6300 3900);
FORCEPROP 0 LAST CDS_SEC 1
J 0
(-6275 4100);
DISPLAY INVISIBLE (-6275 4100);
FORCEADD RES..2
(-8450 4950);
FORCEPROP 1 LAST TOLERANCE 1%
J 0
(-8405 5000);
DISPLAY 0.617021 (-8405 5000);
PAINT SKYBLUE (-8405 5000);
FORCEPROP 1 LASTPIN (-8450 5050) $PN 1
J 0
(-8445 5012);
DISPLAY 0.617021 (-8445 5012);
PAINT WHITE (-8445 5012);
FORCEPROP 1 LASTPIN (-8450 4850) $PN 2
J 0
(-8445 4860);
DISPLAY 0.617021 (-8445 4860);
PAINT WHITE (-8445 4860);
FORCEPROP 1 LAST PACK_TYPE 0402
J 0
(-8410 4800);
DISPLAY 0.617021 (-8410 4800);
PAINT SKYBLUE (-8410 4800);
FORCEPROP 1 LAST PART_NUMBER G21796-026
J 0
(-8410 4850);
DISPLAY 0.617021 (-8410 4850);
PAINT BLUE (-8410 4850);
FORCEPROP 1 LAST MATERIAL CHIP
J 0
(-8410 4900);
DISPLAY 0.617021 (-8410 4900);
PAINT SKYBLUE (-8410 4900);
FORCEPROP 1 LAST WATTAGE 1/16W
J 0
(-8410 4950);
DISPLAY 0.617021 (-8410 4950);
PAINT SKYBLUE (-8410 4950);
FORCEPROP 1 LAST VALUE 1.00K
J 0
(-8405 5050);
DISPLAY 0.617021 (-8405 5050);
PAINT SKYBLUE (-8405 5050);
FORCEPROP 1 LAST LOCATION R25W176
J 0
(-8405 5100);
DISPLAY 0.617021 (-8405 5100);
PAINT AQUA (-8405 5100);
FORCEPROP 1 LAST PATH I14
J 0
(-8400 5125);
DISPLAY 0.978723 (-8400 5125);
PAINT WHITE (-8400 5125);
DISPLAY INVISIBLE (-8400 5125);
FORCEPROP 2 LAST CDS_LOCATION R25W176
J 0
(-8405 5075);
DISPLAY 0.617021 (-8405 5075);
PAINT AQUA (-8405 5075);
DISPLAY INVISIBLE (-8405 5075);
FORCEPROP 2 LAST ROOM PROC_RSTS_PGOODS
J 0
(-8425 4725);
DISPLAY 1.617021 (-8425 4725);
PAINT WHITE (-8425 4725);
DISPLAY INVISIBLE (-8425 4725);
FORCEPROP 2 LAST $SEC 1
J 0
(-8400 5175);
DISPLAY 1.510638 (-8400 5175);
PAINT MONO (-8400 5175);
DISPLAY INVISIBLE (-8400 5175);
FORCEPROP 2 LAST CDS_SEC 1
J 0
(-8400 5175);
DISPLAY 2.276596 (-8400 5175);
PAINT ORANGE (-8400 5175);
DISPLAY INVISIBLE (-8400 5175);
FORCEPROP 2 LAST CDS_LIB mstr_discrete
J 0
(-8450 4950);
DISPLAY 1.617021 (-8450 4950);
PAINT ORANGE (-8450 4950);
DISPLAY INVISIBLE (-8450 4950);
FORCEPROP 2 LAST BOM_COST PROC_SIDEBAND
J 0
(-8450 4950);
DISPLAY 1.617021 (-8450 4950);
PAINT WHITE (-8450 4950);
DISPLAY INVISIBLE (-8450 4950);
FORCEADD GND..1
(-8450 4775);
FORCEPROP 3 LASTPIN (-8450 4825) SIG_NAME GND\g
J 0
(-8440 4835);
DISPLAY 0.659574 (-8440 4835);
PAINT MONO (-8440 4835);
DISPLAY INVISIBLE (-8440 4835);
FORCEPROP 1 LAST PATH I15
J 0
(-8375 4775);
DISPLAY 0.872340 (-8375 4775);
PAINT AQUA (-8375 4775);
DISPLAY INVISIBLE (-8375 4775);
FORCEPROP 2 LAST CDS_LIB mstr_symbols
J 0
(-8450 4775);
PAINT ORANGE (-8450 4775);
DISPLAY INVISIBLE (-8450 4775);
FORCEPROP 1 LAST SIZE 1B
J 0
(-8375 4725);
DISPLAY 1.893617 (-8375 4725);
PAINT GREEN (-8375 4725);
DISPLAY INVISIBLE (-8375 4725);
FORCEPROP 1 LAST VOLTAGE 0.0V
J 0
(-8495 4732);
DISPLAY 0.340426 (-8495 4732);
PAINT SKYBLUE (-8495 4732);
DISPLAY INVISIBLE (-8495 4732);
FORCEPROP 1 LAST BODY_TYPE PLUMBING
J 0
(-8495 4732);
DISPLAY 0.340426 (-8495 4732);
PAINT GREEN (-8495 4732);
DISPLAY INVISIBLE (-8495 4732);
FORCEPROP 1 LAST HDL_POWER GND
J 0
(-8450 4925);
DISPLAY 1.595745 (-8450 4925);
PAINT GREEN (-8450 4925);
DISPLAY INVISIBLE (-8450 4925);
FORCEADD GND..1
(-8150 4775);
FORCEPROP 3 LASTPIN (-8150 4825) SIG_NAME GND\g
J 0
(-8140 4835);
DISPLAY 0.659574 (-8140 4835);
PAINT MONO (-8140 4835);
DISPLAY INVISIBLE (-8140 4835);
FORCEPROP 1 LAST PATH I16
J 0
(-8075 4775);
DISPLAY 0.872340 (-8075 4775);
PAINT AQUA (-8075 4775);
DISPLAY INVISIBLE (-8075 4775);
FORCEPROP 2 LAST CDS_LIB mstr_symbols
J 0
(-8150 4775);
PAINT ORANGE (-8150 4775);
DISPLAY INVISIBLE (-8150 4775);
FORCEPROP 1 LAST SIZE 1B
J 0
(-8075 4725);
DISPLAY 1.893617 (-8075 4725);
PAINT GREEN (-8075 4725);
DISPLAY INVISIBLE (-8075 4725);
FORCEPROP 1 LAST VOLTAGE 0.0V
J 0
(-8195 4732);
DISPLAY 0.340426 (-8195 4732);
PAINT SKYBLUE (-8195 4732);
DISPLAY INVISIBLE (-8195 4732);
FORCEPROP 1 LAST BODY_TYPE PLUMBING
J 0
(-8195 4732);
DISPLAY 0.340426 (-8195 4732);
PAINT GREEN (-8195 4732);
DISPLAY INVISIBLE (-8195 4732);
FORCEPROP 1 LAST HDL_POWER GND
J 0
(-8150 4925);
DISPLAY 1.595745 (-8150 4925);
PAINT GREEN (-8150 4925);
DISPLAY INVISIBLE (-8150 4925);
FORCEADD RES..2
(-8150 4950);
FORCEPROP 1 LAST LOCATION R25W175
J 0
(-8105 5100);
DISPLAY 0.617021 (-8105 5100);
PAINT AQUA (-8105 5100);
FORCEPROP 1 LAST VALUE 1.00K
J 0
(-8105 5050);
DISPLAY 0.617021 (-8105 5050);
PAINT SKYBLUE (-8105 5050);
FORCEPROP 1 LAST TOLERANCE 1%
J 0
(-8105 5000);
DISPLAY 0.617021 (-8105 5000);
PAINT SKYBLUE (-8105 5000);
FORCEPROP 1 LASTPIN (-8150 5050) $PN 1
J 0
(-8145 5012);
DISPLAY 0.617021 (-8145 5012);
PAINT WHITE (-8145 5012);
FORCEPROP 1 LASTPIN (-8150 4850) $PN 2
J 0
(-8145 4860);
DISPLAY 0.617021 (-8145 4860);
PAINT WHITE (-8145 4860);
FORCEPROP 1 LAST PACK_TYPE 0402
J 0
(-8110 4800);
DISPLAY 0.617021 (-8110 4800);
PAINT SKYBLUE (-8110 4800);
FORCEPROP 1 LAST PART_NUMBER G21796-026
J 0
(-8110 4850);
DISPLAY 0.617021 (-8110 4850);
PAINT BLUE (-8110 4850);
FORCEPROP 1 LAST MATERIAL CHIP
J 0
(-8110 4900);
DISPLAY 0.617021 (-8110 4900);
PAINT SKYBLUE (-8110 4900);
FORCEPROP 1 LAST WATTAGE 1/16W
J 0
(-8110 4950);
DISPLAY 0.617021 (-8110 4950);
PAINT SKYBLUE (-8110 4950);
FORCEPROP 1 LAST PATH I17
J 0
(-8100 5125);
DISPLAY 0.978723 (-8100 5125);
PAINT WHITE (-8100 5125);
DISPLAY INVISIBLE (-8100 5125);
FORCEPROP 2 LAST CDS_LOCATION R25W175
J 0
(-8105 5075);
DISPLAY 0.617021 (-8105 5075);
PAINT AQUA (-8105 5075);
DISPLAY INVISIBLE (-8105 5075);
FORCEPROP 2 LAST ROOM PROC_RSTS_PGOODS
J 0
(-8125 4725);
DISPLAY 1.617021 (-8125 4725);
PAINT WHITE (-8125 4725);
DISPLAY INVISIBLE (-8125 4725);
FORCEPROP 2 LAST $SEC 1
J 0
(-8100 5175);
DISPLAY 1.510638 (-8100 5175);
PAINT MONO (-8100 5175);
DISPLAY INVISIBLE (-8100 5175);
FORCEPROP 2 LAST CDS_SEC 1
J 0
(-8100 5175);
DISPLAY 2.276596 (-8100 5175);
PAINT ORANGE (-8100 5175);
DISPLAY INVISIBLE (-8100 5175);
FORCEPROP 2 LAST CDS_LIB mstr_discrete
J 0
(-8150 4950);
DISPLAY 1.617021 (-8150 4950);
PAINT ORANGE (-8150 4950);
DISPLAY INVISIBLE (-8150 4950);
FORCEPROP 2 LAST BOM_COST PROC_SIDEBAND
J 0
(-8150 4950);
DISPLAY 1.617021 (-8150 4950);
PAINT WHITE (-8150 4950);
DISPLAY INVISIBLE (-8150 4950);
FORCEADD OFFPAGE..1
(-8450 5550);
FORCEPROP 2 LAST $XR2 111 
J 0
(-8942 5550);
DISPLAY 0.638298 (-8942 5550);
PAINT MONO (-8942 5550);
FORCEPROP 2 LAST $XR1 118 
J 0
(-8822 5550);
DISPLAY 0.638298 (-8822 5550);
PAINT MONO (-8822 5550);
FORCEPROP 2 LAST $XR0 112 
J 0
(-8702 5550);
DISPLAY 0.638298 (-8702 5550);
PAINT MONO (-8702 5550);
FORCEPROP 2 LAST CDS_LIB mstr_standard
J 0
(-8450 5550);
PAINT ORANGE (-8450 5550);
DISPLAY INVISIBLE (-8450 5550);
FORCEPROP 2 LAST PATH I18
J 0
(-8700 5600);
DISPLAY 1.021277 (-8700 5600);
PAINT ORANGE (-8700 5600);
DISPLAY INVISIBLE (-8700 5600);
FORCEPROP 1 LAST OFFPAGE TRUE
J 0
(-8125 5425);
DISPLAY 1.404255 (-8125 5425);
PAINT GREEN (-8125 5425);
DISPLAY INVISIBLE (-8125 5425);
FORCEPROP 1 LAST COMMENT_BODY TRUE
J 0
(-8325 5450);
DISPLAY 1.404255 (-8325 5450);
PAINT PEACH (-8325 5450);
DISPLAY INVISIBLE (-8325 5450);
FORCEADD OFFPAGE..1
(-8450 5650);
FORCEPROP 2 LAST $XR2 111 
J 0
(-8942 5650);
DISPLAY 0.638298 (-8942 5650);
PAINT MONO (-8942 5650);
FORCEPROP 2 LAST $XR1 118 
J 0
(-8822 5650);
DISPLAY 0.638298 (-8822 5650);
PAINT MONO (-8822 5650);
FORCEPROP 2 LAST $XR0 112 
J 0
(-8702 5650);
DISPLAY 0.638298 (-8702 5650);
PAINT MONO (-8702 5650);
FORCEPROP 2 LAST PATH I19
J 0
(-8700 5700);
DISPLAY 1.021277 (-8700 5700);
PAINT ORANGE (-8700 5700);
DISPLAY INVISIBLE (-8700 5700);
FORCEPROP 2 LAST CDS_LIB mstr_standard
J 0
(-8450 5650);
PAINT ORANGE (-8450 5650);
DISPLAY INVISIBLE (-8450 5650);
FORCEPROP 1 LAST OFFPAGE TRUE
J 0
(-8125 5525);
DISPLAY 1.404255 (-8125 5525);
PAINT GREEN (-8125 5525);
DISPLAY INVISIBLE (-8125 5525);
FORCEPROP 1 LAST COMMENT_BODY TRUE
J 0
(-8325 5550);
DISPLAY 1.404255 (-8325 5550);
PAINT PEACH (-8325 5550);
DISPLAY INVISIBLE (-8325 5550);
FORCEADD RES..2
(-7100 3350);
FORCEPROP 1 LASTPIN (-7100 3250) $PN 2
J 0
(-7095 3260);
DISPLAY 0.617021 (-7095 3260);
PAINT WHITE (-7095 3260);
FORCEPROP 1 LASTPIN (-7100 3450) $PN 1
J 0
(-7095 3412);
DISPLAY 0.617021 (-7095 3412);
PAINT WHITE (-7095 3412);
FORCEPROP 1 LAST MATERIAL CHIP
J 0
(-7060 3300);
DISPLAY 0.617021 (-7060 3300);
PAINT SKYBLUE (-7060 3300);
FORCEPROP 1 LAST TOLERANCE 1%
J 0
(-7055 3400);
DISPLAY 0.617021 (-7055 3400);
PAINT SKYBLUE (-7055 3400);
FORCEPROP 1 LAST VALUE 1.00K
J 0
(-7055 3450);
DISPLAY 0.617021 (-7055 3450);
PAINT SKYBLUE (-7055 3450);
FORCEPROP 1 LAST LOCATION R25W180
J 0
(-7055 3500);
DISPLAY 0.617021 (-7055 3500);
PAINT AQUA (-7055 3500);
FORCEPROP 1 LAST PACK_TYPE 0402
J 0
(-7060 3200);
DISPLAY 0.617021 (-7060 3200);
PAINT SKYBLUE (-7060 3200);
FORCEPROP 1 LAST PART_NUMBER G21796-026
J 0
(-7060 3250);
DISPLAY 0.617021 (-7060 3250);
PAINT BLUE (-7060 3250);
FORCEPROP 1 LAST WATTAGE 1/16W
J 0
(-7060 3350);
DISPLAY 0.617021 (-7060 3350);
PAINT SKYBLUE (-7060 3350);
FORCEPROP 1 LAST PATH I2
J 0
(-7050 3525);
DISPLAY 0.978723 (-7050 3525);
PAINT WHITE (-7050 3525);
DISPLAY INVISIBLE (-7050 3525);
FORCEPROP 2 LAST CDS_LOCATION R25W180
J 0
(-7055 3475);
DISPLAY 0.617021 (-7055 3475);
PAINT AQUA (-7055 3475);
DISPLAY INVISIBLE (-7055 3475);
FORCEPROP 2 LAST BOM_COST PROC_SIDEBAND
J 0
(-7100 3350);
DISPLAY 1.617021 (-7100 3350);
PAINT WHITE (-7100 3350);
DISPLAY INVISIBLE (-7100 3350);
FORCEPROP 2 LAST CDS_LIB mstr_discrete
J 0
(-7100 3350);
DISPLAY 1.617021 (-7100 3350);
PAINT ORANGE (-7100 3350);
DISPLAY INVISIBLE (-7100 3350);
FORCEPROP 2 LAST CDS_SEC 1
J 0
(-7050 3575);
DISPLAY 2.276596 (-7050 3575);
PAINT ORANGE (-7050 3575);
DISPLAY INVISIBLE (-7050 3575);
FORCEPROP 2 LAST $SEC 1
J 0
(-7050 3575);
DISPLAY 1.510638 (-7050 3575);
PAINT MONO (-7050 3575);
DISPLAY INVISIBLE (-7050 3575);
FORCEPROP 2 LAST ROOM PROC_RSTS_PGOODS
J 0
(-7075 3125);
DISPLAY 1.617021 (-7075 3125);
PAINT WHITE (-7075 3125);
DISPLAY INVISIBLE (-7075 3125);
FORCEADD GND..1
(-7750 4825);
FORCEPROP 3 LASTPIN (-7750 4875) SIG_NAME GND\g
J 0
(-7740 4885);
DISPLAY 0.659574 (-7740 4885);
PAINT MONO (-7740 4885);
DISPLAY INVISIBLE (-7740 4885);
FORCEPROP 1 LAST PATH I20
J 0
(-7675 4825);
DISPLAY 0.872340 (-7675 4825);
PAINT AQUA (-7675 4825);
DISPLAY INVISIBLE (-7675 4825);
FORCEPROP 2 LAST CDS_LIB mstr_symbols
J 0
(-7750 4825);
PAINT ORANGE (-7750 4825);
DISPLAY INVISIBLE (-7750 4825);
FORCEPROP 1 LAST SIZE 1B
J 0
(-7675 4775);
DISPLAY 1.893617 (-7675 4775);
PAINT GREEN (-7675 4775);
DISPLAY INVISIBLE (-7675 4775);
FORCEPROP 1 LAST VOLTAGE 0.0V
J 0
(-7795 4782);
DISPLAY 0.340426 (-7795 4782);
PAINT SKYBLUE (-7795 4782);
DISPLAY INVISIBLE (-7795 4782);
FORCEPROP 1 LAST BODY_TYPE PLUMBING
J 0
(-7795 4782);
DISPLAY 0.340426 (-7795 4782);
PAINT GREEN (-7795 4782);
DISPLAY INVISIBLE (-7795 4782);
FORCEPROP 1 LAST HDL_POWER GND
J 0
(-7750 4975);
DISPLAY 1.595745 (-7750 4975);
PAINT GREEN (-7750 4975);
DISPLAY INVISIBLE (-7750 4975);
FORCEADD GND..1
(-6550 5625);
FORCEPROP 3 LASTPIN (-6550 5675) SIG_NAME GND\g
J 0
(-6540 5685);
DISPLAY 0.659574 (-6540 5685);
PAINT MONO (-6540 5685);
DISPLAY INVISIBLE (-6540 5685);
FORCEPROP 1 LAST PATH I21
J 0
(-6475 5625);
DISPLAY 0.872340 (-6475 5625);
PAINT AQUA (-6475 5625);
DISPLAY INVISIBLE (-6475 5625);
FORCEPROP 1 LAST VOLTAGE 0
J 0
(-6550 5625);
PAINT SKYBLUE (-6550 5625);
DISPLAY INVISIBLE (-6550 5625);
FORCEPROP 1 LAST SIZE 1B
J 0
(-6475 5575);
DISPLAY 1.212766 (-6475 5575);
PAINT GREEN (-6475 5575);
DISPLAY INVISIBLE (-6475 5575);
FORCEPROP 2 LAST CDS_LIB mstr_symbols
J 0
(-6550 5625);
PAINT ORANGE (-6550 5625);
DISPLAY INVISIBLE (-6550 5625);
FORCEPROP 1 LAST BODY_TYPE PLUMBING
J 0
(-6595 5582);
DISPLAY 0.340426 (-6595 5582);
PAINT GREEN (-6595 5582);
DISPLAY INVISIBLE (-6595 5582);
FORCEPROP 1 LAST HDL_POWER GND
J 0
(-6550 5775);
DISPLAY 1.212766 (-6550 5775);
PAINT GREEN (-6550 5775);
DISPLAY INVISIBLE (-6550 5775);
FORCEADD P3V3_STBY..1
(-6550 6050);
FORCEPROP 3 LASTPIN (-6550 6000) SIG_NAME P3V3_STBY\g
J 0
(-6540 6010);
DISPLAY 0.659574 (-6540 6010);
PAINT MONO (-6540 6010);
DISPLAY INVISIBLE (-6540 6010);
FORCEPROP 1 LAST PATH I22
J 0
(-6505 6052);
DISPLAY 0.340426 (-6505 6052);
PAINT GREEN (-6505 6052);
DISPLAY INVISIBLE (-6505 6052);
FORCEPROP 2 LAST CDS_LIB mstr_symbols
J 0
(-6550 6050);
PAINT ORANGE (-6550 6050);
DISPLAY INVISIBLE (-6550 6050);
FORCEPROP 1 LAST SIZE 1B
J 0
(-6505 6072);
DISPLAY 0.340426 (-6505 6072);
PAINT GREEN (-6505 6072);
DISPLAY INVISIBLE (-6505 6072);
FORCEPROP 1 LAST VOLTAGE 3.3V
J 0
(-6595 6007);
DISPLAY 0.340426 (-6595 6007);
PAINT SKYBLUE (-6595 6007);
DISPLAY INVISIBLE (-6595 6007);
FORCEPROP 1 LAST BODY_TYPE PLUMBING
J 0
(-6595 6007);
DISPLAY 0.340426 (-6595 6007);
PAINT GREEN (-6595 6007);
DISPLAY INVISIBLE (-6595 6007);
FORCEPROP 1 LAST HDL_POWER P3V3_STBY
J 0
(-6850 5925);
DISPLAY 0.872340 (-6850 5925);
PAINT ORANGE (-6850 5925);
DISPLAY INVISIBLE (-6850 5925);
FORCEADD CAP..1
(-6550 5800);
FORCEPROP 1 LAST PACK_TYPE 0402
J 0
(-6500 5600);
DISPLAY 0.617021 (-6500 5600);
PAINT SKYBLUE (-6500 5600);
FORCEPROP 1 LAST MATERIAL X6S
J 0
(-6500 5700);
DISPLAY 0.617021 (-6500 5700);
PAINT SKYBLUE (-6500 5700);
FORCEPROP 1 LAST VOLTAGE 16V
J 0
(-6500 5800);
DISPLAY 0.617021 (-6500 5800);
PAINT SKYBLUE (-6500 5800);
FORCEPROP 1 LAST TOLERANCE 10%
J 0
(-6500 5750);
DISPLAY 0.617021 (-6500 5750);
PAINT SKYBLUE (-6500 5750);
FORCEPROP 1 LASTPIN (-6550 5700) $PN 2
J 0
(-6540 5680);
DISPLAY 0.617021 (-6540 5680);
PAINT ORANGE (-6540 5680);
FORCEPROP 1 LAST LOCATION C25W92
J 0
(-6500 5900);
DISPLAY 0.617021 (-6500 5900);
PAINT AQUA (-6500 5900);
FORCEPROP 1 LAST VALUE 1.0UF
J 0
(-6500 5850);
DISPLAY 0.617021 (-6500 5850);
PAINT SKYBLUE (-6500 5850);
FORCEPROP 1 LASTPIN (-6550 5900) $PN 1
J 0
(-6540 5880);
DISPLAY 0.617021 (-6540 5880);
PAINT ORANGE (-6540 5880);
FORCEPROP 1 LAST PART_NUMBER D97712-011
J 0
(-6500 5650);
DISPLAY 0.617021 (-6500 5650);
PAINT BLUE (-6500 5650);
FORCEPROP 1 LAST PATH I23
J 0
(-6500 5950);
DISPLAY 0.978723 (-6500 5950);
PAINT WHITE (-6500 5950);
DISPLAY INVISIBLE (-6500 5950);
FORCEPROP 2 LAST CDS_LOCATION C25W92
J 0
(-6500 5900);
DISPLAY 0.617021 (-6500 5900);
PAINT AQUA (-6500 5900);
DISPLAY INVISIBLE (-6500 5900);
FORCEPROP 2 LAST SEC_TYPE 0402
J 0
(-6500 6000);
DISPLAY 1.021277 (-6500 6000);
PAINT ORANGE (-6500 6000);
DISPLAY INVISIBLE (-6500 6000);
FORCEPROP 2 LAST CDS_LIB mstr_discrete
J 0
(-6550 5800);
PAINT ORANGE (-6550 5800);
DISPLAY INVISIBLE (-6550 5800);
FORCEPROP 0 LAST BOM_COST PROC
J 0
(-6500 6000);
DISPLAY 1.021277 (-6500 6000);
PAINT ORANGE (-6500 6000);
DISPLAY INVISIBLE (-6500 6000);
FORCEPROP 2 LAST SEC 1
J 0
(-6500 6000);
DISPLAY 0.680851 (-6500 6000);
PAINT MONO (-6500 6000);
DISPLAY INVISIBLE (-6500 6000);
FORCEPROP 0 LAST ROOM PROC_SIDEBAND
J 0
(-6500 6000);
DISPLAY 1.021277 (-6500 6000);
PAINT ORANGE (-6500 6000);
DISPLAY INVISIBLE (-6500 6000);
FORCEPROP 0 LAST CDS_SEC 1
J 0
(-6500 5950);
DISPLAY INVISIBLE (-6500 5950);
FORCEADD GND..1
(-5750 5575);
FORCEPROP 3 LASTPIN (-5750 5625) SIG_NAME GND\g
J 0
(-5740 5635);
DISPLAY 0.659574 (-5740 5635);
PAINT MONO (-5740 5635);
DISPLAY INVISIBLE (-5740 5635);
FORCEPROP 1 LAST PATH I25
J 0
(-5675 5575);
DISPLAY 0.872340 (-5675 5575);
PAINT AQUA (-5675 5575);
DISPLAY INVISIBLE (-5675 5575);
FORCEPROP 1 LAST SIZE 1B
J 0
(-5675 5525);
DISPLAY 1.212766 (-5675 5525);
PAINT GREEN (-5675 5525);
DISPLAY INVISIBLE (-5675 5525);
FORCEPROP 2 LAST CDS_LIB mstr_symbols
J 0
(-5750 5575);
PAINT ORANGE (-5750 5575);
DISPLAY INVISIBLE (-5750 5575);
FORCEPROP 1 LAST VOLTAGE 0
J 0
(-5750 5575);
PAINT SKYBLUE (-5750 5575);
DISPLAY INVISIBLE (-5750 5575);
FORCEPROP 1 LAST BODY_TYPE PLUMBING
J 0
(-5795 5532);
DISPLAY 0.340426 (-5795 5532);
PAINT GREEN (-5795 5532);
DISPLAY INVISIBLE (-5795 5532);
FORCEPROP 1 LAST HDL_POWER GND
J 0
(-5750 5725);
DISPLAY 1.212766 (-5750 5725);
PAINT GREEN (-5750 5725);
DISPLAY INVISIBLE (-5750 5725);
FORCEADD RES..1
(-6000 5450);
FORCEPROP 1 LAST MATERIAL CHIP
J 0
(-5550 5400);
DISPLAY 0.617021 (-5550 5400);
PAINT SKYBLUE (-5550 5400);
FORCEPROP 1 LAST WATTAGE 1/16W
J 0
(-5850 5400);
DISPLAY 0.617021 (-5850 5400);
PAINT SKYBLUE (-5850 5400);
FORCEPROP 1 LAST PACK_TYPE 0402
J 0
(-5700 5400);
DISPLAY 0.617021 (-5700 5400);
PAINT SKYBLUE (-5700 5400);
FORCEPROP 1 LAST TOLERANCE 1%
J 0
(-5950 5400);
DISPLAY 0.617021 (-5950 5400);
PAINT SKYBLUE (-5950 5400);
FORCEPROP 1 LAST VALUE 1.00K
J 0
(-6100 5400);
DISPLAY 0.617021 (-6100 5400);
PAINT SKYBLUE (-6100 5400);
FORCEPROP 1 LASTPIN (-5900 5450) $PN 2
J 0
(-5938 5462);
DISPLAY 0.617021 (-5938 5462);
PAINT ORANGE (-5938 5462);
FORCEPROP 1 LAST LOCATION R25W166
J 0
(-6100 5500);
DISPLAY 0.617021 (-6100 5500);
PAINT AQUA (-6100 5500);
FORCEPROP 1 LASTPIN (-6100 5450) $PN 1
J 0
(-6088 5462);
DISPLAY 0.617021 (-6088 5462);
PAINT ORANGE (-6088 5462);
FORCEPROP 1 LAST PART_NUMBER G21796-026
J 0
(-5900 5500);
DISPLAY 0.617021 (-5900 5500);
PAINT BLUE (-5900 5500);
FORCEPROP 2 LAST CDS_LOCATION R25W166
J 0
(-6050 5500);
DISPLAY 0.617021 (-6050 5500);
PAINT AQUA (-6050 5500);
DISPLAY INVISIBLE (-6050 5500);
FORCEPROP 2 LAST ROOM PROC_SIDEBAND
J 0
(-6050 5600);
PAINT PEACH (-6050 5600);
DISPLAY INVISIBLE (-6050 5600);
FORCEPROP 2 LAST SEC 1
J 0
(-6050 5650);
DISPLAY 0.680851 (-6050 5650);
PAINT MONO (-6050 5650);
DISPLAY INVISIBLE (-6050 5650);
FORCEPROP 2 LAST BOM_COST PROC_SIDEBAND
J 0
(-6000 5450);
PAINT MONO (-6000 5450);
DISPLAY INVISIBLE (-6000 5450);
FORCEPROP 2 LAST CDS_LIB mstr_discrete
J 0
(-6000 5450);
PAINT ORANGE (-6000 5450);
DISPLAY INVISIBLE (-6000 5450);
FORCEPROP 2 LAST SEC_TYPE 0402
J 0
(-6050 5650);
DISPLAY 1.021277 (-6050 5650);
PAINT ORANGE (-6050 5650);
DISPLAY INVISIBLE (-6050 5650);
FORCEPROP 0 LAST CDS_SEC 1
J 0
(-5900 5550);
DISPLAY INVISIBLE (-5900 5550);
FORCEPROP 1 LAST PATH I26
J 0
(-6050 5600);
DISPLAY 0.978723 (-6050 5600);
PAINT WHITE (-6050 5600);
DISPLAY INVISIBLE (-6050 5600);
FORCEADD CAP_A..1
(-6050 5850);
FORCEPROP 1 LAST PACK_TYPE 0402V
J 0
(-6000 5700);
DISPLAY 0.617021 (-6000 5700);
PAINT SKYBLUE (-6000 5700);
FORCEPROP 1 LAST PART_NUMBER A36096-030
J 0
(-6000 5750);
DISPLAY 0.617021 (-6000 5750);
PAINT BLUE (-6000 5750);
FORCEPROP 1 LAST MATERIAL X7R
J 0
(-6000 5800);
DISPLAY 0.617021 (-6000 5800);
PAINT SKYBLUE (-6000 5800);
FORCEPROP 1 LAST TOLERANCE 10%
J 0
(-6000 5850);
DISPLAY 0.617021 (-6000 5850);
PAINT SKYBLUE (-6000 5850);
FORCEPROP 1 LAST LOCATION C25W93
J 0
(-6000 6000);
DISPLAY 0.617021 (-6000 6000);
PAINT AQUA (-6000 6000);
FORCEPROP 1 LAST VALUE 0.1UF
J 0
(-6000 5950);
DISPLAY 0.617021 (-6000 5950);
PAINT SKYBLUE (-6000 5950);
FORCEPROP 1 LAST VOLTAGE 16V
J 0
(-6000 5900);
DISPLAY 0.617021 (-6000 5900);
PAINT SKYBLUE (-6000 5900);
FORCEPROP 1 LASTPIN (-6050 5750) $PN 2
J 0
(-6040 5730);
DISPLAY 0.617021 (-6040 5730);
PAINT MONO (-6040 5730);
FORCEPROP 1 LASTPIN (-6050 5950) $PN 1
J 0
(-6040 5930);
DISPLAY 0.617021 (-6040 5930);
PAINT MONO (-6040 5930);
FORCEPROP 1 LAST PATH I27
J 0
(-6000 6000);
DISPLAY 0.978723 (-6000 6000);
PAINT WHITE (-6000 6000);
DISPLAY INVISIBLE (-6000 6000);
FORCEPROP 2 LAST CDS_LOCATION C25W93
J 0
(-6000 5950);
DISPLAY 0.617021 (-6000 5950);
PAINT AQUA (-6000 5950);
DISPLAY INVISIBLE (-6000 5950);
FORCEPROP 2 LAST SEC 1
J 0
(-6000 6050);
DISPLAY 0.936170 (-6000 6050);
PAINT MONO (-6000 6050);
DISPLAY INVISIBLE (-6000 6050);
FORCEPROP 2 LAST SEC_TYPE 0402V
J 0
(-6000 6050);
PAINT MONO (-6000 6050);
DISPLAY INVISIBLE (-6000 6050);
FORCEPROP 2 LAST CDS_SEC 1
J 0
(-6000 6000);
PAINT ORANGE (-6000 6000);
DISPLAY INVISIBLE (-6000 6000);
FORCEPROP 2 LAST CDS_LIB dev_discrete
J 0
(-6050 5850);
PAINT ORANGE (-6050 5850);
DISPLAY INVISIBLE (-6050 5850);
FORCEPROP 2 LAST BOM_COST PROC_SIDEBAND
J 0
(-6050 5850);
PAINT MONO (-6050 5850);
DISPLAY INVISIBLE (-6050 5850);
FORCEPROP 2 LAST ROOM PROC_SIDEBAND
J 0
(-6000 5600);
DISPLAY 0.978723 (-6000 5600);
PAINT ORANGE (-6000 5600);
DISPLAY INVISIBLE (-6000 5600);
FORCEADD RES..2
(-5750 5850);
FORCEPROP 1 LAST VALUE 100.0
J 0
(-5705 5950);
DISPLAY 0.617021 (-5705 5950);
PAINT SKYBLUE (-5705 5950);
FORCEPROP 1 LAST PART_NUMBER G21796-017
J 0
(-5710 5750);
DISPLAY 0.617021 (-5710 5750);
PAINT BLUE (-5710 5750);
FORCEPROP 1 LAST MATERIAL CHIP
J 0
(-5710 5800);
DISPLAY 0.617021 (-5710 5800);
PAINT SKYBLUE (-5710 5800);
FORCEPROP 1 LAST PACK_TYPE 0402
J 0
(-5710 5700);
DISPLAY 0.617021 (-5710 5700);
PAINT SKYBLUE (-5710 5700);
FORCEPROP 1 LAST LOCATION R25W165
J 0
(-5705 6000);
DISPLAY 0.617021 (-5705 6000);
PAINT AQUA (-5705 6000);
FORCEPROP 1 LASTPIN (-5750 5750) $PN 2
J 0
(-5745 5760);
DISPLAY 0.617021 (-5745 5760);
PAINT MONO (-5745 5760);
FORCEPROP 1 LASTPIN (-5750 5950) $PN 1
J 0
(-5745 5912);
DISPLAY 0.617021 (-5745 5912);
PAINT MONO (-5745 5912);
FORCEPROP 1 LAST TOLERANCE 1%
J 0
(-5705 5900);
DISPLAY 0.617021 (-5705 5900);
PAINT SKYBLUE (-5705 5900);
FORCEPROP 1 LAST WATTAGE 1/16W
J 0
(-5710 5850);
DISPLAY 0.617021 (-5710 5850);
PAINT SKYBLUE (-5710 5850);
FORCEPROP 1 LAST PATH I28
J 0
(-5700 6025);
DISPLAY 0.978723 (-5700 6025);
PAINT WHITE (-5700 6025);
DISPLAY INVISIBLE (-5700 6025);
FORCEPROP 2 LAST CDS_LOCATION R25W165
J 0
(-5705 5975);
DISPLAY 0.617021 (-5705 5975);
PAINT AQUA (-5705 5975);
DISPLAY INVISIBLE (-5705 5975);
FORCEPROP 2 LAST ROOM PROC_SIDEBAND
J 2
(-5450 5625);
DISPLAY 0.978723 (-5450 5625);
PAINT ORANGE (-5450 5625);
DISPLAY INVISIBLE (-5450 5625);
FORCEPROP 2 LAST SEC 1
J 0
(-5700 6075);
DISPLAY 0.936170 (-5700 6075);
PAINT MONO (-5700 6075);
DISPLAY INVISIBLE (-5700 6075);
FORCEPROP 2 LAST BOM_COST PROC_SIDEBAND
J 0
(-5750 5850);
PAINT MONO (-5750 5850);
DISPLAY INVISIBLE (-5750 5850);
FORCEPROP 2 LAST CDS_LIB mstr_discrete
J 2
(-5750 5850);
PAINT ORANGE (-5750 5850);
DISPLAY INVISIBLE (-5750 5850);
FORCEPROP 2 LAST SEC_TYPE 0402
J 0
(-5700 6075);
PAINT MONO (-5700 6075);
DISPLAY INVISIBLE (-5700 6075);
FORCEPROP 0 LAST CDS_SEC 1
J 0
(-5700 6050);
DISPLAY INVISIBLE (-5700 6050);
FORCEADD RES..2
(-5750 6250);
FORCEPROP 1 LAST LOCATION R25W164
J 0
(-5705 6400);
DISPLAY 0.617021 (-5705 6400);
PAINT AQUA (-5705 6400);
FORCEPROP 1 LAST PACK_TYPE 0402
J 0
(-5710 6100);
DISPLAY 0.638298 (-5710 6100);
PAINT SKYBLUE (-5710 6100);
FORCEPROP 0 LAST POP NOPOP
J 0
(-5700 6050);
DISPLAY 0.638298 (-5700 6050);
PAINT RED (-5700 6050);
FORCEPROP 1 LAST VALUE 49.9
J 0
(-5705 6350);
DISPLAY 0.617021 (-5705 6350);
PAINT SKYBLUE (-5705 6350);
FORCEPROP 1 LAST TOLERANCE 1%
J 0
(-5705 6300);
DISPLAY 0.638298 (-5705 6300);
PAINT SKYBLUE (-5705 6300);
FORCEPROP 1 LASTPIN (-5750 6350) $PN 1
J 0
(-5745 6312);
DISPLAY 0.617021 (-5745 6312);
PAINT WHITE (-5745 6312);
FORCEPROP 1 LASTPIN (-5750 6150) $PN 2
J 0
(-5745 6160);
DISPLAY 0.617021 (-5745 6160);
PAINT WHITE (-5745 6160);
FORCEPROP 1 LAST WATTAGE 1/16W
J 0
(-5710 6250);
DISPLAY 0.638298 (-5710 6250);
PAINT SKYBLUE (-5710 6250);
FORCEPROP 1 LAST MATERIAL CHIP
J 0
(-5710 6200);
DISPLAY 0.617021 (-5710 6200);
PAINT SKYBLUE (-5710 6200);
FORCEPROP 1 LAST PART_NUMBER G21796-047
J 0
(-5710 6150);
DISPLAY 0.617021 (-5710 6150);
PAINT BLUE (-5710 6150);
FORCEPROP 0 LAST CDS_SEC 1
J 0
(-5700 6450);
DISPLAY INVISIBLE (-5700 6450);
FORCEPROP 2 LAST ROOM CPU0
J 0
(-5725 6025);
PAINT ORANGE (-5725 6025);
DISPLAY INVISIBLE (-5725 6025);
FORCEPROP 2 LAST CDS_LIB mstr_discrete
J 0
(-5750 6250);
PAINT ORANGE (-5750 6250);
DISPLAY INVISIBLE (-5750 6250);
FORCEPROP 2 LAST BOM_COST PROC_SIDEBAND
J 0
(-5750 6250);
PAINT MONO (-5750 6250);
DISPLAY INVISIBLE (-5750 6250);
FORCEPROP 2 LAST SEC_TYPE 0402
J 0
(-5700 6500);
DISPLAY 1.021277 (-5700 6500);
PAINT ORANGE (-5700 6500);
DISPLAY INVISIBLE (-5700 6500);
FORCEPROP 2 LAST SEC 1
J 0
(-5700 6500);
DISPLAY 0.680851 (-5700 6500);
PAINT MONO (-5700 6500);
DISPLAY INVISIBLE (-5700 6500);
FORCEPROP 2 LAST CDS_LOCATION R25W164
J 0
(-5705 6375);
DISPLAY 0.617021 (-5705 6375);
PAINT AQUA (-5705 6375);
DISPLAY INVISIBLE (-5705 6375);
FORCEPROP 1 LAST PATH I29
J 0
(-5700 6425);
DISPLAY 0.978723 (-5700 6425);
PAINT WHITE (-5700 6425);
DISPLAY INVISIBLE (-5700 6425);
FORCEADD P3V3_STBY..1
(-7100 3550);
FORCEPROP 3 LASTPIN (-7100 3500) SIG_NAME P3V3_STBY\g
J 0
(-7090 3510);
DISPLAY 0.659574 (-7090 3510);
PAINT MONO (-7090 3510);
DISPLAY INVISIBLE (-7090 3510);
FORCEPROP 1 LAST PATH I3
J 0
(-7055 3552);
DISPLAY 0.340426 (-7055 3552);
PAINT GREEN (-7055 3552);
DISPLAY INVISIBLE (-7055 3552);
FORCEPROP 1 LAST VOLTAGE 3.3V
J 0
(-7145 3507);
DISPLAY 0.340426 (-7145 3507);
PAINT SKYBLUE (-7145 3507);
DISPLAY INVISIBLE (-7145 3507);
FORCEPROP 1 LAST SIZE 1B
J 0
(-7055 3572);
DISPLAY 0.340426 (-7055 3572);
PAINT GREEN (-7055 3572);
DISPLAY INVISIBLE (-7055 3572);
FORCEPROP 2 LAST CDS_LIB mstr_symbols
J 0
(-7100 3550);
PAINT ORANGE (-7100 3550);
DISPLAY INVISIBLE (-7100 3550);
FORCEPROP 1 LAST BODY_TYPE PLUMBING
J 0
(-7145 3507);
DISPLAY 0.340426 (-7145 3507);
PAINT GREEN (-7145 3507);
DISPLAY INVISIBLE (-7145 3507);
FORCEPROP 1 LAST HDL_POWER P3V3_STBY
J 0
(-7400 3425);
DISPLAY 0.872340 (-7400 3425);
PAINT ORANGE (-7400 3425);
DISPLAY INVISIBLE (-7400 3425);
FORCEADD P1V05_PCH_STBY..1
(-5750 6450);
FORCEPROP 3 LASTPIN (-5750 6400) SIG_NAME P1V05_PCH_STBY\g
J 0
(-5740 6410);
DISPLAY 0.659574 (-5740 6410);
PAINT MONO (-5740 6410);
DISPLAY INVISIBLE (-5740 6410);
FORCEPROP 1 LAST VOLTAGE 1.05V
J 0
(-5795 6407);
DISPLAY 0.340426 (-5795 6407);
PAINT SKYBLUE (-5795 6407);
DISPLAY INVISIBLE (-5795 6407);
FORCEPROP 2 LAST CDS_LIB mstr_symbols
J 0
(-5750 6450);
PAINT ORANGE (-5750 6450);
DISPLAY INVISIBLE (-5750 6450);
FORCEPROP 1 LAST PATH I30
J 0
(-5700 6475);
DISPLAY 0.872340 (-5700 6475);
PAINT AQUA (-5700 6475);
DISPLAY INVISIBLE (-5700 6475);
FORCEPROP 1 LAST BODY_TYPE PLUMBING
J 0
(-5795 6407);
DISPLAY 0.340426 (-5795 6407);
PAINT GREEN (-5795 6407);
DISPLAY INVISIBLE (-5795 6407);
FORCEPROP 1 LAST HDL_POWER P1V05_PCH_STBY
J 0
(-5750 6500);
DISPLAY 0.872340 (-5750 6500);
PAINT GREEN (-5750 6500);
DISPLAY INVISIBLE (-5750 6500);
FORCEADD OFFPAGE..2
(-5400 3900);
FORCEPROP 2 LAST $XR2 56 
J 0
(-5001 3900);
DISPLAY 0.638298 (-5001 3900);
PAINT MONO (-5001 3900);
FORCEPROP 2 LAST $XR1 22 
J 0
(-5091 3900);
DISPLAY 0.638298 (-5091 3900);
PAINT MONO (-5091 3900);
FORCEPROP 2 LAST $XR0 111 
J 0
(-5211 3900);
DISPLAY 0.638298 (-5211 3900);
PAINT MONO (-5211 3900);
FORCEPROP 2 LAST PATH I31
J 0
(-5000 3950);
DISPLAY 1.021277 (-5000 3950);
PAINT ORANGE (-5000 3950);
DISPLAY INVISIBLE (-5000 3950);
FORCEPROP 2 LAST CDS_LIB mstr_standard
J 2
(-5400 3900);
PAINT ORANGE (-5400 3900);
DISPLAY INVISIBLE (-5400 3900);
FORCEPROP 1 LAST OFFPAGE TRUE
J 0
(-5075 3775);
DISPLAY 0.872340 (-5075 3775);
PAINT GREEN (-5075 3775);
DISPLAY INVISIBLE (-5075 3775);
FORCEPROP 1 LAST COMMENT_BODY TRUE
J 0
(-5445 3805);
DISPLAY 0.872340 (-5445 3805);
PAINT GREEN (-5445 3805);
DISPLAY INVISIBLE (-5445 3805);
FORCEADD GND..1
(-5300 5375);
FORCEPROP 3 LASTPIN (-5300 5425) SIG_NAME GND\g
J 0
(-5290 5435);
DISPLAY 0.659574 (-5290 5435);
PAINT MONO (-5290 5435);
DISPLAY INVISIBLE (-5290 5435);
FORCEPROP 1 LAST PATH I32
J 0
(-5225 5375);
DISPLAY 0.872340 (-5225 5375);
PAINT AQUA (-5225 5375);
DISPLAY INVISIBLE (-5225 5375);
FORCEPROP 1 LAST SIZE 1B
J 0
(-5225 5325);
DISPLAY 1.170213 (-5225 5325);
PAINT GREEN (-5225 5325);
DISPLAY INVISIBLE (-5225 5325);
FORCEPROP 2 LAST CDS_LIB mstr_symbols
J 0
(-5300 5375);
PAINT ORANGE (-5300 5375);
DISPLAY INVISIBLE (-5300 5375);
FORCEPROP 1 LAST VOLTAGE 0
J 0
(-5300 5375);
PAINT SKYBLUE (-5300 5375);
DISPLAY INVISIBLE (-5300 5375);
FORCEPROP 1 LAST BODY_TYPE PLUMBING
J 0
(-5345 5332);
DISPLAY 0.340426 (-5345 5332);
PAINT GREEN (-5345 5332);
DISPLAY INVISIBLE (-5345 5332);
FORCEPROP 1 LAST HDL_POWER GND
J 0
(-5300 5525);
DISPLAY 1.170213 (-5300 5525);
PAINT GREEN (-5300 5525);
DISPLAY INVISIBLE (-5300 5525);
FORCEADD GTL2014..1
R 2
(-7200 5300);
FORCEPROP 2 LASTPIN (-7650 5000) $PN 11
J 2
(-7660 5010);
DISPLAY 0.617021 (-7660 5010);
PAINT ORANGE (-7660 5010);
FORCEPROP 2 LASTPIN (-6750 5300) $PN 9
J 0
(-6740 5310);
DISPLAY 0.617021 (-6740 5310);
PAINT ORANGE (-6740 5310);
FORCEPROP 2 LASTPIN (-6750 5250) $PN 10
J 0
(-6740 5260);
DISPLAY 0.617021 (-6740 5260);
PAINT ORANGE (-6740 5260);
FORCEPROP 2 LASTPIN (-6750 5150) $PN 13
J 0
(-6740 5160);
DISPLAY 0.617021 (-6740 5160);
PAINT ORANGE (-6740 5160);
FORCEPROP 2 LASTPIN (-6750 5200) $PN 12
J 0
(-6740 5210);
DISPLAY 0.617021 (-6740 5210);
PAINT ORANGE (-6740 5210);
FORCEPROP 2 LASTPIN (-7650 4900) $PN 7
J 2
(-7660 4910);
DISPLAY 0.617021 (-7660 4910);
PAINT ORANGE (-7660 4910);
FORCEPROP 2 LASTPIN (-7650 4950) $PN 8
J 2
(-7660 4960);
DISPLAY 0.617021 (-7660 4960);
PAINT ORANGE (-7660 4960);
FORCEPROP 1 LAST PART_NUMBER D66151-001
J 2
(-6800 4775);
DISPLAY 0.617021 (-6800 4775);
PAINT BLUE (-6800 4775);
FORCEPROP 2 LASTPIN (-6750 5550) $PN 4
J 0
(-6740 5560);
DISPLAY 0.617021 (-6740 5560);
PAINT ORANGE (-6740 5560);
FORCEPROP 2 LASTPIN (-7650 5200) $PN 3
J 2
(-7660 5210);
DISPLAY 0.617021 (-7660 5210);
PAINT ORANGE (-7660 5210);
FORCEPROP 2 LASTPIN (-7650 5250) $PN 5
J 2
(-7660 5260);
DISPLAY 0.617021 (-7660 5260);
PAINT ORANGE (-7660 5260);
FORCEPROP 2 LASTPIN (-6750 5600) $PN 14
J 0
(-6740 5610);
DISPLAY 0.617021 (-6740 5610);
PAINT ORANGE (-6740 5610);
FORCEPROP 2 LASTPIN (-7650 5150) $PN 2
J 2
(-7660 5160);
DISPLAY 0.617021 (-7660 5160);
PAINT ORANGE (-7660 5160);
FORCEPROP 1 LAST MATERIAL IC
J 2
(-6800 5800);
DISPLAY 0.617021 (-6800 5800);
PAINT SKYBLUE (-6800 5800);
FORCEPROP 2 LASTPIN (-7650 5300) $PN 6
J 2
(-7660 5310);
DISPLAY 0.617021 (-7660 5310);
PAINT ORANGE (-7660 5310);
FORCEPROP 2 LASTPIN (-6750 5450) $PN 1
J 0
(-6740 5460);
DISPLAY 0.617021 (-6740 5460);
PAINT ORANGE (-6740 5460);
FORCEPROP 1 LAST LOCATION U25W11
J 2
(-6800 5850);
DISPLAY 0.617021 (-6800 5850);
PAINT AQUA (-6800 5850);
FORCEPROP 1 LAST PATH I33
J 2
(-7200 5800);
PAINT GREEN (-7200 5800);
DISPLAY INVISIBLE (-7200 5800);
FORCEPROP 2 LAST CDS_LOCATION U25W11
J 2
(-6800 5850);
DISPLAY 0.617021 (-6800 5850);
PAINT AQUA (-6800 5850);
DISPLAY INVISIBLE (-6800 5850);
FORCEPROP 2 LAST ROOM PROC_SIDEBAND
J 2
(-6800 5950);
PAINT MONO (-6800 5950);
DISPLAY INVISIBLE (-6800 5950);
FORCEPROP 2 LAST SEC 1
J 0
(-6800 5900);
DISPLAY 0.680851 (-6800 5900);
PAINT MONO (-6800 5900);
DISPLAY INVISIBLE (-6800 5900);
FORCEPROP 2 LAST CDS_LIB mstr_digital
J 0
(-7200 5300);
PAINT ORANGE (-7200 5300);
DISPLAY INVISIBLE (-7200 5300);
FORCEPROP 2 LAST BOM_COST PROC_SIDEBAND
J 2
(-7200 5300);
PAINT MONO (-7200 5300);
DISPLAY INVISIBLE (-7200 5300);
FORCEPROP 2 LAST SEC_TYPE SM
J 0
(-6800 5900);
DISPLAY 1.021277 (-6800 5900);
PAINT ORANGE (-6800 5900);
DISPLAY INVISIBLE (-6800 5900);
FORCEPROP 1 LAST PACK_TYPE SM
J 2
(-6800 5900);
PAINT SKYBLUE (-6800 5900);
DISPLAY INVISIBLE (-6800 5900);
FORCEPROP 0 LAST CDS_SEC 1
J 0
(-6800 5900);
DISPLAY INVISIBLE (-6800 5900);
FORCEADD OFFPAGE..2
(-6050 5200);
FORCEPROP 2 LAST $XR0 146 
J 0
(-5861 5200);
DISPLAY 0.638298 (-5861 5200);
PAINT MONO (-5861 5200);
FORCEPROP 2 LAST ROOM CPU_XDP_DEBUG
J 0
(-5850 5250);
DISPLAY 1.617021 (-5850 5250);
PAINT WHITE (-5850 5250);
DISPLAY INVISIBLE (-5850 5250);
FORCEPROP 2 LAST BOM_COST DEBUG
J 0
(-5850 5250);
DISPLAY 1.617021 (-5850 5250);
PAINT WHITE (-5850 5250);
DISPLAY INVISIBLE (-5850 5250);
FORCEPROP 2 LAST CDS_LIB mstr_standard
J 0
(-6050 5200);
DISPLAY 2.212766 (-6050 5200);
PAINT ORANGE (-6050 5200);
DISPLAY INVISIBLE (-6050 5200);
FORCEPROP 2 LAST PATH I34
J 0
(-5600 5250);
DISPLAY 1.021277 (-5600 5250);
PAINT ORANGE (-5600 5250);
DISPLAY INVISIBLE (-5600 5250);
FORCEPROP 1 LAST OFFPAGE TRUE
J 0
(-5725 5075);
PAINT GREEN (-5725 5075);
DISPLAY INVISIBLE (-5725 5075);
FORCEPROP 1 LAST COMMENT_BODY TRUE
J 0
(-6095 5105);
DISPLAY 1.893617 (-6095 5105);
PAINT PEACH (-6095 5105);
DISPLAY INVISIBLE (-6095 5105);
FORCEADD OFFPAGE..1
(-8200 3100);
FORCEPROP 2 LAST $XR0 144 
J 0
(-8452 3100);
DISPLAY 0.638298 (-8452 3100);
PAINT MONO (-8452 3100);
FORCEPROP 2 LAST CDS_LIB mstr_standard
J 0
(-8200 3100);
PAINT ORANGE (-8200 3100);
DISPLAY INVISIBLE (-8200 3100);
FORCEPROP 2 LAST PATH I35
J 0
(-8450 3150);
DISPLAY 1.021277 (-8450 3150);
PAINT ORANGE (-8450 3150);
DISPLAY INVISIBLE (-8450 3150);
FORCEPROP 1 LAST OFFPAGE TRUE
J 0
(-7875 2975);
DISPLAY 1.404255 (-7875 2975);
PAINT GREEN (-7875 2975);
DISPLAY INVISIBLE (-7875 2975);
FORCEPROP 1 LAST COMMENT_BODY TRUE
J 0
(-8075 3000);
DISPLAY 1.404255 (-8075 3000);
PAINT PEACH (-8075 3000);
DISPLAY INVISIBLE (-8075 3000);
FORCEADD 374R2F-1-GP..1
(-5150 6225);
FORCEPROP 1 LAST VALUE 374R2F-1-GP
J 0
(-5100 6300);
DISPLAY 0.617021 (-5100 6300);
PAINT GREEN (-5100 6300);
FORCEPROP 1 LAST LOCATION R25W183
J 0
(-5100 6355);
DISPLAY 0.617021 (-5100 6355);
PAINT GREEN (-5100 6355);
FORCEPROP 2 LAST ATTRIBUTE 374 OHM
J 0
(-5100 6250);
DISPLAY 0.638298 (-5100 6250);
PAINT GREEN (-5100 6250);
FORCEPROP 2 LAST TOLERANCE 1%
J 0
(-5100 6200);
DISPLAY 0.638298 (-5100 6200);
PAINT GREEN (-5100 6200);
FORCEPROP 2 LAST RATED 1/16W
J 0
(-5100 6150);
DISPLAY 0.638298 (-5100 6150);
PAINT GREEN (-5100 6150);
FORCEPROP 2 LAST PACK_SIZE 0402
J 0
(-5100 6100);
DISPLAY 0.638298 (-5100 6100);
PAINT GREEN (-5100 6100);
FORCEPROP 1 LAST PATH I36
J 0
(-5150 6225);
DISPLAY 0.617021 (-5150 6225);
PAINT GREEN (-5150 6225);
DISPLAY INVISIBLE (-5150 6225);
FORCEPROP 1 LAST PACK_TYPE SMD-RG
J 0
(-5150 6225);
DISPLAY 0.617021 (-5150 6225);
PAINT GREEN (-5150 6225);
DISPLAY INVISIBLE (-5150 6225);
FORCEPROP 1 LAST PART_NUMBER 64.37405.6DL
J 0
(-5150 6225);
DISPLAY 0.617021 (-5150 6225);
PAINT GREEN (-5150 6225);
DISPLAY INVISIBLE (-5150 6225);
FORCEPROP 2 LAST CDS_LIB w_hdl
J 0
(-5150 6225);
DISPLAY INVISIBLE (-5150 6225);
FORCEPROP 1 LAST CDS_LMAN_SYM_OUTLINE -50,75,50,-75
J 0
(-5150 6225);
DISPLAY 0.468085 (-5150 6225);
PAINT GREEN (-5150 6225);
DISPLAY INVISIBLE (-5150 6225);
FORCEADD P3V3_STBY..1
(-5150 6450);
FORCEPROP 3 LASTPIN (-5150 6400) SIG_NAME P3V3_STBY\g
J 0
(-5140 6410);
DISPLAY 0.659574 (-5140 6410);
PAINT MONO (-5140 6410);
DISPLAY INVISIBLE (-5140 6410);
FORCEPROP 2 LAST CDS_LIB mstr_symbols
J 0
(-5150 6450);
PAINT ORANGE (-5150 6450);
DISPLAY INVISIBLE (-5150 6450);
FORCEPROP 1 LAST SIZE 1B
J 0
(-5105 6472);
DISPLAY 0.340426 (-5105 6472);
PAINT GREEN (-5105 6472);
DISPLAY INVISIBLE (-5105 6472);
FORCEPROP 1 LAST VOLTAGE 3.3V
J 0
(-5195 6407);
DISPLAY 0.340426 (-5195 6407);
PAINT SKYBLUE (-5195 6407);
DISPLAY INVISIBLE (-5195 6407);
FORCEPROP 1 LAST PATH I37
J 0
(-5105 6452);
DISPLAY 0.340426 (-5105 6452);
PAINT GREEN (-5105 6452);
DISPLAY INVISIBLE (-5105 6452);
FORCEPROP 1 LAST BODY_TYPE PLUMBING
J 0
(-5195 6407);
DISPLAY 0.340426 (-5195 6407);
PAINT GREEN (-5195 6407);
DISPLAY INVISIBLE (-5195 6407);
FORCEPROP 1 LAST HDL_POWER P3V3_STBY
J 0
(-5450 6325);
DISPLAY 0.872340 (-5450 6325);
PAINT ORANGE (-5450 6325);
DISPLAY INVISIBLE (-5450 6325);
FORCEADD TTL3126..3
(-2900 5000);
FORCEPROP 2 LASTPIN (-2700 5350) $PN 11
J 0
(-2690 5360);
DISPLAY 0.617021 (-2690 5360);
PAINT WHITE (-2690 5360);
FORCEPROP 2 LASTPIN (-2700 5150) $PN 8
J 0
(-2690 5160);
DISPLAY 0.617021 (-2690 5160);
PAINT WHITE (-2690 5160);
FORCEPROP 2 LASTPIN (-2700 4750) $PN 3
J 0
(-2690 4760);
DISPLAY 0.617021 (-2690 4760);
PAINT WHITE (-2690 4760);
FORCEPROP 1 LAST MATERIAL IC
J 0
(-3050 5525);
DISPLAY 0.617021 (-3050 5525);
PAINT SKYBLUE (-3050 5525);
FORCEPROP 1 LAST LOCATION U25W16
J 0
(-3050 5575);
DISPLAY 0.617021 (-3050 5575);
PAINT AQUA (-3050 5575);
FORCEPROP 2 LASTPIN (-2700 4950) $PN 6
J 0
(-2690 4960);
DISPLAY 0.617021 (-2690 4960);
PAINT WHITE (-2690 4960);
FORCEPROP 2 LASTPIN (-3100 5350) $PN 12
J 2
(-3110 5360);
DISPLAY 0.617021 (-3110 5360);
PAINT WHITE (-3110 5360);
FORCEPROP 2 LASTPIN (-3100 5150) $PN 9
J 2
(-3110 5160);
DISPLAY 0.617021 (-3110 5160);
PAINT WHITE (-3110 5160);
FORCEPROP 2 LASTPIN (-3100 5250) $PN 13
J 2
(-3110 5260);
DISPLAY 0.617021 (-3110 5260);
PAINT WHITE (-3110 5260);
FORCEPROP 1 LAST VALUE 74CBTLV3126
J 0
(-3050 5475);
DISPLAY 0.617021 (-3050 5475);
PAINT SKYBLUE (-3050 5475);
FORCEPROP 2 LASTPIN (-3100 4650) $PN 1
J 2
(-3110 4660);
DISPLAY 0.617021 (-3110 4660);
PAINT WHITE (-3110 4660);
FORCEPROP 2 LASTPIN (-3100 4750) $PN 2
J 2
(-3110 4760);
DISPLAY 0.617021 (-3110 4760);
PAINT WHITE (-3110 4760);
FORCEPROP 2 LASTPIN (-3100 4850) $PN 4
J 2
(-3110 4860);
DISPLAY 0.617021 (-3110 4860);
PAINT WHITE (-3110 4860);
FORCEPROP 2 LASTPIN (-3100 4950) $PN 5
J 2
(-3110 4960);
DISPLAY 0.617021 (-3110 4960);
PAINT WHITE (-3110 4960);
FORCEPROP 2 LASTPIN (-3100 5050) $PN 10
J 2
(-3110 5060);
DISPLAY 0.617021 (-3110 5060);
PAINT WHITE (-3110 5060);
FORCEPROP 1 LAST PART_NUMBER D18317-001
J 0
(-3050 4525);
DISPLAY 0.617021 (-3050 4525);
PAINT BLUE (-3050 4525);
FORCEPROP 1 LAST POWER_GROUP VCC=P3V3_STBY;GND=GND
J 0
(-3050 4475);
DISPLAY 0.617021 (-3050 4475);
PAINT ORANGE (-3050 4475);
FORCEPROP 1 LAST PACK_TYPE QFNLF
J 0
(-3050 5625);
DISPLAY 1.595745 (-3050 5625);
PAINT SKYBLUE (-3050 5625);
DISPLAY INVISIBLE (-3050 5625);
FORCEPROP 1 LAST HAS_FIXED_SIZE 4B
J 0
(-3050 4425);
DISPLAY 1.595745 (-3050 4425);
PAINT BLUE (-3050 4425);
DISPLAY INVISIBLE (-3050 4425);
FORCEPROP 2 LAST CDS_LIB mstr_ttl
J 0
(-2900 5000);
PAINT ORANGE (-2900 5000);
DISPLAY INVISIBLE (-2900 5000);
FORCEPROP 0 LAST ROOM DEBUG
J 0
(-3050 5675);
DISPLAY 1.021277 (-3050 5675);
PAINT ORANGE (-3050 5675);
DISPLAY INVISIBLE (-3050 5675);
FORCEPROP 0 LASTPIN (-2700 5350) CDS_SEC 4
J 0
(-2690 5407);
DISPLAY 0.808511 (-2690 5407);
DISPLAY INVISIBLE (-2690 5407);
FORCEPROP 0 LASTPIN (-2700 5350) $SEC 4
J 0
(-2690 5360);
DISPLAY 0.808511 (-2690 5360);
DISPLAY INVISIBLE (-2690 5360);
FORCEPROP 0 LASTPIN (-2700 5150) CDS_SEC 3
J 0
(-2690 5207);
DISPLAY 0.808511 (-2690 5207);
DISPLAY INVISIBLE (-2690 5207);
FORCEPROP 0 LASTPIN (-2700 5150) $SEC 3
J 0
(-2690 5160);
DISPLAY 0.808511 (-2690 5160);
DISPLAY INVISIBLE (-2690 5160);
FORCEPROP 0 LASTPIN (-2700 4950) CDS_SEC 2
J 0
(-2690 5007);
DISPLAY 0.808511 (-2690 5007);
DISPLAY INVISIBLE (-2690 5007);
FORCEPROP 0 LASTPIN (-2700 4950) $SEC 2
J 0
(-2690 4960);
DISPLAY 0.808511 (-2690 4960);
DISPLAY INVISIBLE (-2690 4960);
FORCEPROP 0 LASTPIN (-2700 4750) CDS_SEC 1
J 0
(-2690 4807);
DISPLAY 0.808511 (-2690 4807);
DISPLAY INVISIBLE (-2690 4807);
FORCEPROP 0 LASTPIN (-2700 4750) $SEC 1
J 0
(-2690 4760);
DISPLAY 0.808511 (-2690 4760);
DISPLAY INVISIBLE (-2690 4760);
FORCEPROP 0 LASTPIN (-3100 5150) CDS_SEC 3
J 2
(-3110 5207);
DISPLAY 0.808511 (-3110 5207);
DISPLAY INVISIBLE (-3110 5207);
FORCEPROP 0 LASTPIN (-3100 5150) $SEC 3
J 2
(-3110 5160);
DISPLAY 0.808511 (-3110 5160);
DISPLAY INVISIBLE (-3110 5160);
FORCEPROP 0 LASTPIN (-3100 5350) CDS_SEC 4
J 2
(-3110 5407);
DISPLAY 0.808511 (-3110 5407);
DISPLAY INVISIBLE (-3110 5407);
FORCEPROP 0 LASTPIN (-3100 5350) $SEC 4
J 2
(-3110 5360);
DISPLAY 0.808511 (-3110 5360);
DISPLAY INVISIBLE (-3110 5360);
FORCEPROP 0 LASTPIN (-3100 4950) CDS_SEC 2
J 2
(-3110 5007);
DISPLAY 0.808511 (-3110 5007);
DISPLAY INVISIBLE (-3110 5007);
FORCEPROP 0 LASTPIN (-3100 4950) $SEC 2
J 2
(-3110 4960);
DISPLAY 0.808511 (-3110 4960);
DISPLAY INVISIBLE (-3110 4960);
FORCEPROP 0 LASTPIN (-3100 4750) CDS_SEC 1
J 2
(-3110 4807);
DISPLAY 0.808511 (-3110 4807);
DISPLAY INVISIBLE (-3110 4807);
FORCEPROP 0 LASTPIN (-3100 4750) $SEC 1
J 2
(-3110 4760);
DISPLAY 0.808511 (-3110 4760);
DISPLAY INVISIBLE (-3110 4760);
FORCEPROP 0 LASTPIN (-3100 5250) CDS_SEC 4
J 2
(-3110 5307);
DISPLAY 0.808511 (-3110 5307);
DISPLAY INVISIBLE (-3110 5307);
FORCEPROP 0 LASTPIN (-3100 5250) $SEC 4
J 2
(-3110 5260);
DISPLAY 0.808511 (-3110 5260);
DISPLAY INVISIBLE (-3110 5260);
FORCEPROP 0 LASTPIN (-3100 5050) CDS_SEC 3
J 2
(-3110 5107);
DISPLAY 0.808511 (-3110 5107);
DISPLAY INVISIBLE (-3110 5107);
FORCEPROP 0 LASTPIN (-3100 5050) $SEC 3
J 2
(-3110 5060);
DISPLAY 0.808511 (-3110 5060);
DISPLAY INVISIBLE (-3110 5060);
FORCEPROP 0 LASTPIN (-3100 4850) CDS_SEC 2
J 2
(-3110 4907);
DISPLAY 0.808511 (-3110 4907);
DISPLAY INVISIBLE (-3110 4907);
FORCEPROP 0 LASTPIN (-3100 4850) $SEC 2
J 2
(-3110 4860);
DISPLAY 0.808511 (-3110 4860);
DISPLAY INVISIBLE (-3110 4860);
FORCEPROP 0 LASTPIN (-3100 4650) CDS_SEC 1
J 2
(-3110 4707);
DISPLAY 0.808511 (-3110 4707);
DISPLAY INVISIBLE (-3110 4707);
FORCEPROP 0 LASTPIN (-3100 4650) $SEC 1
J 2
(-3110 4660);
DISPLAY 0.808511 (-3110 4660);
DISPLAY INVISIBLE (-3110 4660);
FORCEPROP 1 LAST PATH I38
J 0
(-2600 5525);
DISPLAY 0.978723 (-2600 5525);
PAINT BLUE (-2600 5525);
DISPLAY INVISIBLE (-2600 5525);
FORCEPROP 2 LAST CDS_LOCATION U25W16
J 0
(-3050 5575);
DISPLAY 0.617021 (-3050 5575);
PAINT AQUA (-3050 5575);
DISPLAY INVISIBLE (-3050 5575);
FORCEADD P3V3_STBY..1
(-2250 4600);
FORCEPROP 3 LASTPIN (-2250 4550) SIG_NAME P3V3_STBY\g
J 0
(-2240 4560);
DISPLAY 0.659574 (-2240 4560);
PAINT MONO (-2240 4560);
DISPLAY INVISIBLE (-2240 4560);
FORCEPROP 1 LAST PATH I39
J 0
(-2205 4602);
DISPLAY 0.340426 (-2205 4602);
PAINT GREEN (-2205 4602);
DISPLAY INVISIBLE (-2205 4602);
FORCEPROP 1 LAST VOLTAGE 3.3V
J 0
(-2295 4557);
DISPLAY 0.340426 (-2295 4557);
PAINT SKYBLUE (-2295 4557);
DISPLAY INVISIBLE (-2295 4557);
FORCEPROP 2 LAST CDS_LIB mstr_symbols
J 0
(-2250 4600);
PAINT MONO (-2250 4600);
DISPLAY INVISIBLE (-2250 4600);
FORCEPROP 1 LAST SIZE 1B
J 0
(-2205 4622);
DISPLAY 0.340426 (-2205 4622);
PAINT GREEN (-2205 4622);
DISPLAY INVISIBLE (-2205 4622);
FORCEPROP 1 LAST BODY_TYPE PLUMBING
J 0
(-2295 4557);
DISPLAY 0.340426 (-2295 4557);
PAINT GREEN (-2295 4557);
DISPLAY INVISIBLE (-2295 4557);
FORCEPROP 1 LAST HDL_POWER P3V3_STBY
J 0
(-2550 4475);
DISPLAY 0.872340 (-2550 4475);
PAINT ORANGE (-2550 4475);
DISPLAY INVISIBLE (-2550 4475);
FORCEADD CAP_A..1
(-6700 3350);
FORCEPROP 1 LAST TOLERANCE 10%
J 0
(-6650 3350);
DISPLAY 0.617021 (-6650 3350);
PAINT SKYBLUE (-6650 3350);
FORCEPROP 1 LAST PACK_TYPE 0402V
J 0
(-6650 3200);
DISPLAY 0.617021 (-6650 3200);
PAINT SKYBLUE (-6650 3200);
FORCEPROP 1 LAST VOLTAGE 16V
J 0
(-6650 3400);
DISPLAY 0.617021 (-6650 3400);
PAINT SKYBLUE (-6650 3400);
FORCEPROP 1 LASTPIN (-6700 3450) $PN 1
J 0
(-6690 3430);
DISPLAY 0.617021 (-6690 3430);
PAINT ORANGE (-6690 3430);
FORCEPROP 1 LASTPIN (-6700 3250) $PN 2
J 0
(-6690 3230);
DISPLAY 0.617021 (-6690 3230);
PAINT ORANGE (-6690 3230);
FORCEPROP 1 LAST PART_NUMBER A36096-030
J 0
(-6650 3250);
DISPLAY 0.617021 (-6650 3250);
PAINT BLUE (-6650 3250);
FORCEPROP 1 LAST VALUE 0.1UF
J 0
(-6650 3450);
DISPLAY 0.617021 (-6650 3450);
PAINT SKYBLUE (-6650 3450);
FORCEPROP 1 LAST LOCATION C25W97
J 0
(-6650 3500);
DISPLAY 0.617021 (-6650 3500);
PAINT AQUA (-6650 3500);
FORCEPROP 1 LAST MATERIAL X7R
J 0
(-6650 3300);
DISPLAY 0.617021 (-6650 3300);
PAINT SKYBLUE (-6650 3300);
FORCEPROP 1 LAST PATH I4
J 0
(-6650 3500);
DISPLAY 0.978723 (-6650 3500);
PAINT WHITE (-6650 3500);
DISPLAY INVISIBLE (-6650 3500);
FORCEPROP 2 LAST CDS_LOCATION C25W97
J 0
(-6650 3450);
DISPLAY 0.617021 (-6650 3450);
PAINT AQUA (-6650 3450);
DISPLAY INVISIBLE (-6650 3450);
FORCEPROP 0 LAST ROOM CPU_FANS
J 0
(-6650 3550);
DISPLAY 1.021277 (-6650 3550);
PAINT ORANGE (-6650 3550);
DISPLAY INVISIBLE (-6650 3550);
FORCEPROP 0 LAST BOM_COST SM_THERM
J 0
(-6650 3650);
DISPLAY 1.021277 (-6650 3650);
PAINT ORANGE (-6650 3650);
DISPLAY INVISIBLE (-6650 3650);
FORCEPROP 2 LAST SEC_TYPE 0402V
J 0
(-6650 3550);
DISPLAY 1.021277 (-6650 3550);
PAINT ORANGE (-6650 3550);
DISPLAY INVISIBLE (-6650 3550);
FORCEPROP 2 LAST SEC 1
J 0
(-6650 3550);
DISPLAY 0.680851 (-6650 3550);
PAINT MONO (-6650 3550);
DISPLAY INVISIBLE (-6650 3550);
FORCEPROP 2 LAST CDS_SEC 1
J 0
(-6650 3500);
PAINT ORANGE (-6650 3500);
DISPLAY INVISIBLE (-6650 3500);
FORCEPROP 2 LAST CDS_LIB dev_discrete
J 0
(-6700 3350);
PAINT ORANGE (-6700 3350);
DISPLAY INVISIBLE (-6700 3350);
FORCEADD CAP..1
(-2250 4400);
FORCEPROP 1 LASTPIN (-2250 4300) $PN 2
J 0
(-2240 4280);
DISPLAY 0.617021 (-2240 4280);
PAINT ORANGE (-2240 4280);
FORCEPROP 1 LAST MATERIAL X6S
J 0
(-2200 4300);
DISPLAY 0.617021 (-2200 4300);
PAINT SKYBLUE (-2200 4300);
FORCEPROP 1 LAST PART_NUMBER D97712-011
J 0
(-2200 4250);
DISPLAY 0.617021 (-2200 4250);
PAINT BLUE (-2200 4250);
FORCEPROP 1 LAST PACK_TYPE 0402
J 0
(-2200 4200);
DISPLAY 0.617021 (-2200 4200);
PAINT SKYBLUE (-2200 4200);
FORCEPROP 1 LASTPIN (-2250 4500) $PN 1
J 0
(-2240 4480);
DISPLAY 0.617021 (-2240 4480);
PAINT ORANGE (-2240 4480);
FORCEPROP 1 LAST VOLTAGE 16V
J 0
(-2200 4400);
DISPLAY 0.617021 (-2200 4400);
PAINT SKYBLUE (-2200 4400);
FORCEPROP 1 LAST VALUE 1.0UF
J 0
(-2200 4450);
DISPLAY 0.617021 (-2200 4450);
PAINT SKYBLUE (-2200 4450);
FORCEPROP 1 LAST LOCATION C25W98
J 0
(-2200 4500);
DISPLAY 0.617021 (-2200 4500);
PAINT AQUA (-2200 4500);
FORCEPROP 1 LAST TOLERANCE 10%
J 0
(-2200 4350);
DISPLAY 0.617021 (-2200 4350);
PAINT SKYBLUE (-2200 4350);
FORCEPROP 0 LAST CDS_SEC 1
J 0
(-2200 4550);
DISPLAY INVISIBLE (-2200 4550);
FORCEPROP 2 LAST CDS_LIB mstr_discrete
J 0
(-2250 4400);
PAINT MONO (-2250 4400);
DISPLAY INVISIBLE (-2250 4400);
FORCEPROP 2 LAST SEC_TYPE 0402
J 0
(-2200 4600);
DISPLAY 1.021277 (-2200 4600);
PAINT ORANGE (-2200 4600);
DISPLAY INVISIBLE (-2200 4600);
FORCEPROP 2 LAST SEC 1
J 0
(-2200 4600);
DISPLAY 0.680851 (-2200 4600);
PAINT MONO (-2200 4600);
DISPLAY INVISIBLE (-2200 4600);
FORCEPROP 0 LAST ROOM DEBUG
J 0
(-2200 4600);
DISPLAY 1.021277 (-2200 4600);
PAINT ORANGE (-2200 4600);
DISPLAY INVISIBLE (-2200 4600);
FORCEPROP 1 LAST PATH I40
J 0
(-2200 4550);
DISPLAY 0.978723 (-2200 4550);
PAINT WHITE (-2200 4550);
DISPLAY INVISIBLE (-2200 4550);
FORCEPROP 2 LAST CDS_LOCATION C25W98
J 0
(-2200 4500);
DISPLAY 0.617021 (-2200 4500);
PAINT AQUA (-2200 4500);
DISPLAY INVISIBLE (-2200 4500);
FORCEADD GND..1
(-2250 4225);
FORCEPROP 3 LASTPIN (-2250 4275) SIG_NAME GND\g
J 0
(-2240 4285);
DISPLAY 0.659574 (-2240 4285);
PAINT MONO (-2240 4285);
DISPLAY INVISIBLE (-2240 4285);
FORCEPROP 1 LAST PATH I41
J 0
(-2175 4225);
DISPLAY 0.872340 (-2175 4225);
PAINT AQUA (-2175 4225);
DISPLAY INVISIBLE (-2175 4225);
FORCEPROP 1 LAST SIZE 1B
J 0
(-2175 4175);
DISPLAY 2.382979 (-2175 4175);
PAINT GREEN (-2175 4175);
DISPLAY INVISIBLE (-2175 4175);
FORCEPROP 2 LAST CDS_LIB mstr_symbols
J 0
(-2250 4225);
PAINT MONO (-2250 4225);
DISPLAY INVISIBLE (-2250 4225);
FORCEPROP 1 LAST VOLTAGE 0.0V
J 0
(-2295 4182);
DISPLAY 0.340426 (-2295 4182);
PAINT SKYBLUE (-2295 4182);
DISPLAY INVISIBLE (-2295 4182);
FORCEPROP 1 LAST BODY_TYPE PLUMBING
J 0
(-2295 4182);
DISPLAY 0.340426 (-2295 4182);
PAINT GREEN (-2295 4182);
DISPLAY INVISIBLE (-2295 4182);
FORCEPROP 1 LAST HDL_POWER GND
J 0
(-2250 4375);
PAINT GREEN (-2250 4375);
DISPLAY INVISIBLE (-2250 4375);
FORCEADD OFFPAGE..2
(-2050 5350);
FORCEPROP 2 LAST $XR0 254 
J 0
(-1861 5350);
DISPLAY 0.638298 (-1861 5350);
PAINT MONO (-1861 5350);
FORCEPROP 2 LAST PATH I42
J 0
(-1850 5400);
DISPLAY 1.021277 (-1850 5400);
PAINT ORANGE (-1850 5400);
DISPLAY INVISIBLE (-1850 5400);
FORCEPROP 2 LAST ROOM CPU_XDP_DEBUG
J 0
(-1850 5400);
DISPLAY 1.617021 (-1850 5400);
PAINT WHITE (-1850 5400);
DISPLAY INVISIBLE (-1850 5400);
FORCEPROP 2 LAST BOM_COST DEBUG
J 0
(-1850 5400);
DISPLAY 1.617021 (-1850 5400);
PAINT WHITE (-1850 5400);
DISPLAY INVISIBLE (-1850 5400);
FORCEPROP 2 LAST CDS_LIB mstr_standard
J 0
(-2050 5350);
DISPLAY 2.212766 (-2050 5350);
PAINT ORANGE (-2050 5350);
DISPLAY INVISIBLE (-2050 5350);
FORCEPROP 1 LAST OFFPAGE TRUE
J 0
(-1725 5225);
PAINT GREEN (-1725 5225);
DISPLAY INVISIBLE (-1725 5225);
FORCEPROP 1 LAST COMMENT_BODY TRUE
J 0
(-2095 5255);
DISPLAY 1.893617 (-2095 5255);
PAINT PEACH (-2095 5255);
DISPLAY INVISIBLE (-2095 5255);
FORCEADD OFFPAGE..2
(-2050 4750);
FORCEPROP 2 LAST $XR0 254 
J 0
(-1861 4750);
DISPLAY 0.638298 (-1861 4750);
PAINT MONO (-1861 4750);
FORCEPROP 2 LAST PATH I44
J 0
(-1850 4800);
DISPLAY 1.021277 (-1850 4800);
PAINT ORANGE (-1850 4800);
DISPLAY INVISIBLE (-1850 4800);
FORCEPROP 2 LAST CDS_LIB mstr_standard
J 0
(-2050 4750);
DISPLAY 2.212766 (-2050 4750);
PAINT ORANGE (-2050 4750);
DISPLAY INVISIBLE (-2050 4750);
FORCEPROP 2 LAST BOM_COST DEBUG
J 0
(-1850 4800);
DISPLAY 1.617021 (-1850 4800);
PAINT WHITE (-1850 4800);
DISPLAY INVISIBLE (-1850 4800);
FORCEPROP 2 LAST ROOM CPU_XDP_DEBUG
J 0
(-1850 4800);
DISPLAY 1.617021 (-1850 4800);
PAINT WHITE (-1850 4800);
DISPLAY INVISIBLE (-1850 4800);
FORCEPROP 1 LAST OFFPAGE TRUE
J 0
(-1725 4625);
PAINT GREEN (-1725 4625);
DISPLAY INVISIBLE (-1725 4625);
FORCEPROP 1 LAST COMMENT_BODY TRUE
J 0
(-2095 4655);
DISPLAY 1.893617 (-2095 4655);
PAINT PEACH (-2095 4655);
DISPLAY INVISIBLE (-2095 4655);
FORCEADD OFFPAGE..2
(-2050 4950);
FORCEPROP 2 LAST $XR0 254 
J 0
(-1861 4950);
DISPLAY 0.638298 (-1861 4950);
PAINT MONO (-1861 4950);
FORCEPROP 2 LAST PATH I45
J 0
(-1850 5000);
DISPLAY 1.021277 (-1850 5000);
PAINT ORANGE (-1850 5000);
DISPLAY INVISIBLE (-1850 5000);
FORCEPROP 2 LAST ROOM CPU_XDP_DEBUG
J 0
(-1850 5000);
DISPLAY 1.617021 (-1850 5000);
PAINT WHITE (-1850 5000);
DISPLAY INVISIBLE (-1850 5000);
FORCEPROP 2 LAST BOM_COST DEBUG
J 0
(-1850 5000);
DISPLAY 1.617021 (-1850 5000);
PAINT WHITE (-1850 5000);
DISPLAY INVISIBLE (-1850 5000);
FORCEPROP 2 LAST CDS_LIB mstr_standard
J 0
(-2050 4950);
DISPLAY 2.212766 (-2050 4950);
PAINT ORANGE (-2050 4950);
DISPLAY INVISIBLE (-2050 4950);
FORCEPROP 1 LAST OFFPAGE TRUE
J 0
(-1725 4825);
PAINT GREEN (-1725 4825);
DISPLAY INVISIBLE (-1725 4825);
FORCEPROP 1 LAST COMMENT_BODY TRUE
J 0
(-2095 4855);
DISPLAY 1.893617 (-2095 4855);
PAINT PEACH (-2095 4855);
DISPLAY INVISIBLE (-2095 4855);
FORCEADD OFFPAGE..4
(-2050 5150);
FORCEPROP 2 LAST $XR0 255 
J 0
(-1864 5150);
DISPLAY 0.638298 (-1864 5150);
PAINT MONO (-1864 5150);
FORCEPROP 2 LAST CDS_LIB mstr_standard
J 0
(-2050 5150);
PAINT MONO (-2050 5150);
DISPLAY INVISIBLE (-2050 5150);
FORCEPROP 2 LAST PATH I46
J 0
(-1850 5200);
DISPLAY 1.021277 (-1850 5200);
PAINT ORANGE (-1850 5200);
DISPLAY INVISIBLE (-1850 5200);
FORCEPROP 1 LAST OFFPAGE TRUE
J 0
(-1725 5025);
DISPLAY 0.872340 (-1725 5025);
PAINT GREEN (-1725 5025);
DISPLAY INVISIBLE (-1725 5025);
FORCEPROP 1 LAST COMMENT_BODY TRUE
J 0
(-2075 5050);
DISPLAY 0.872340 (-2075 5050);
PAINT GREEN (-2075 5050);
DISPLAY INVISIBLE (-2075 5050);
FORCEADD OFFPAGE..1
(-3750 5350);
FORCEPROP 2 LAST $XR0 147 
J 0
(-4002 5350);
DISPLAY 0.638298 (-4002 5350);
PAINT MONO (-4002 5350);
FORCEPROP 2 LAST PATH I47
J 0
(-4000 5400);
DISPLAY 1.021277 (-4000 5400);
PAINT ORANGE (-4000 5400);
DISPLAY INVISIBLE (-4000 5400);
FORCEPROP 2 LAST CDS_LIB mstr_standard
J 0
(-3750 5350);
PAINT ORANGE (-3750 5350);
DISPLAY INVISIBLE (-3750 5350);
FORCEPROP 1 LAST OFFPAGE TRUE
J 0
(-3425 5225);
DISPLAY 1.404255 (-3425 5225);
PAINT GREEN (-3425 5225);
DISPLAY INVISIBLE (-3425 5225);
FORCEPROP 1 LAST COMMENT_BODY TRUE
J 0
(-3625 5250);
DISPLAY 1.404255 (-3625 5250);
PAINT PEACH (-3625 5250);
DISPLAY INVISIBLE (-3625 5250);
FORCEADD OFFPAGE..1
(-3750 4950);
FORCEPROP 2 LAST $XR1 189 
J 0
(-4122 4950);
DISPLAY 0.638298 (-4122 4950);
PAINT MONO (-4122 4950);
FORCEPROP 2 LAST $XR0 144 
J 0
(-4002 4950);
DISPLAY 0.638298 (-4002 4950);
PAINT MONO (-4002 4950);
FORCEPROP 2 LAST PATH I48
J 0
(-4000 5000);
DISPLAY 1.021277 (-4000 5000);
PAINT ORANGE (-4000 5000);
DISPLAY INVISIBLE (-4000 5000);
FORCEPROP 2 LAST CDS_LIB mstr_standard
J 0
(-3750 4950);
PAINT ORANGE (-3750 4950);
DISPLAY INVISIBLE (-3750 4950);
FORCEPROP 1 LAST OFFPAGE TRUE
J 0
(-3425 4825);
DISPLAY 1.404255 (-3425 4825);
PAINT GREEN (-3425 4825);
DISPLAY INVISIBLE (-3425 4825);
FORCEPROP 1 LAST COMMENT_BODY TRUE
J 0
(-3625 4850);
DISPLAY 1.404255 (-3625 4850);
PAINT PEACH (-3625 4850);
DISPLAY INVISIBLE (-3625 4850);
FORCEADD OFFPAGE..1
(-3750 4750);
FORCEPROP 2 LAST $XR1 189 
J 0
(-4122 4750);
DISPLAY 0.638298 (-4122 4750);
PAINT MONO (-4122 4750);
FORCEPROP 2 LAST $XR0 144 
J 0
(-4002 4750);
DISPLAY 0.638298 (-4002 4750);
PAINT MONO (-4002 4750);
FORCEPROP 2 LAST PATH I49
J 0
(-4000 4800);
DISPLAY 1.021277 (-4000 4800);
PAINT ORANGE (-4000 4800);
DISPLAY INVISIBLE (-4000 4800);
FORCEPROP 2 LAST CDS_LIB mstr_standard
J 0
(-3750 4750);
PAINT ORANGE (-3750 4750);
DISPLAY INVISIBLE (-3750 4750);
FORCEPROP 1 LAST OFFPAGE TRUE
J 0
(-3425 4625);
DISPLAY 1.404255 (-3425 4625);
PAINT GREEN (-3425 4625);
DISPLAY INVISIBLE (-3425 4625);
FORCEPROP 1 LAST COMMENT_BODY TRUE
J 0
(-3625 4650);
DISPLAY 1.404255 (-3625 4650);
PAINT PEACH (-3625 4650);
DISPLAY INVISIBLE (-3625 4650);
FORCEADD GND..1
(-6700 3175);
FORCEPROP 3 LASTPIN (-6700 3225) SIG_NAME GND\g
J 0
(-6690 3235);
DISPLAY 0.659574 (-6690 3235);
PAINT MONO (-6690 3235);
DISPLAY INVISIBLE (-6690 3235);
FORCEPROP 1 LAST PATH I5
J 0
(-6625 3175);
DISPLAY 0.872340 (-6625 3175);
PAINT AQUA (-6625 3175);
DISPLAY INVISIBLE (-6625 3175);
FORCEPROP 1 LAST VOLTAGE 0.0V
J 0
(-6745 3132);
DISPLAY 0.340426 (-6745 3132);
PAINT SKYBLUE (-6745 3132);
DISPLAY INVISIBLE (-6745 3132);
FORCEPROP 2 LAST CDS_LIB mstr_symbols
J 0
(-6700 3175);
PAINT ORANGE (-6700 3175);
DISPLAY INVISIBLE (-6700 3175);
FORCEPROP 1 LAST SIZE 1B
J 0
(-6625 3125);
DISPLAY 1.170213 (-6625 3125);
PAINT AQUA (-6625 3125);
DISPLAY INVISIBLE (-6625 3125);
FORCEPROP 1 LAST BODY_TYPE PLUMBING
J 0
(-6745 3132);
DISPLAY 0.340426 (-6745 3132);
PAINT GREEN (-6745 3132);
DISPLAY INVISIBLE (-6745 3132);
FORCEPROP 1 LAST HDL_POWER GND
J 0
(-6700 3325);
DISPLAY 1.170213 (-6700 3325);
PAINT GREEN (-6700 3325);
DISPLAY INVISIBLE (-6700 3325);
FORCEADD OFFPAGE..5
(-3750 5150);
FORCEPROP 2 LAST $XR1 189 
J 0
(-4125 5150);
DISPLAY 0.638298 (-4125 5150);
PAINT MONO (-4125 5150);
FORCEPROP 2 LAST $XR0 144 
J 0
(-4005 5150);
DISPLAY 0.638298 (-4005 5150);
PAINT MONO (-4005 5150);
FORCEPROP 2 LAST CDS_LIB mstr_standard
J 0
(-3750 5150);
PAINT MONO (-3750 5150);
DISPLAY INVISIBLE (-3750 5150);
FORCEPROP 2 LAST PATH I50
J 0
(-3950 5200);
DISPLAY 1.021277 (-3950 5200);
PAINT ORANGE (-3950 5200);
DISPLAY INVISIBLE (-3950 5200);
FORCEPROP 1 LAST OFFPAGE TRUE
J 0
(-3425 5025);
DISPLAY 0.872340 (-3425 5025);
PAINT GREEN (-3425 5025);
DISPLAY INVISIBLE (-3425 5025);
FORCEPROP 1 LAST COMMENT_BODY TRUE
J 0
(-3650 5075);
DISPLAY 0.872340 (-3650 5075);
PAINT GREEN (-3650 5075);
DISPLAY INVISIBLE (-3650 5075);
FORCEADD FET_N..8
(-3250 3050);
FORCEPROP 1 LASTPIN (-3250 3250) $PN 3
J 2
(-3197 3215);
DISPLAY 0.872340 (-3197 3215);
PAINT WHITE (-3197 3215);
FORCEPROP 1 LASTPIN (-3450 2950) $PN 1
J 2
(-3447 2965);
DISPLAY 0.872340 (-3447 2965);
PAINT WHITE (-3447 2965);
FORCEPROP 1 LASTPIN (-3250 2850) $PN 2
J 2
(-3192 2850);
DISPLAY 0.872340 (-3192 2850);
PAINT WHITE (-3192 2850);
FORCEPROP 1 LAST LOCATION Q25W5
J 0
(-3050 3050);
DISPLAY 0.617021 (-3050 3050);
PAINT AQUA (-3050 3050);
FORCEPROP 1 LAST VALUE 2N7002
J 0
(-3050 3000);
DISPLAY 0.617021 (-3050 3000);
PAINT SKYBLUE (-3050 3000);
FORCEPROP 1 LAST MATERIAL FET
J 0
(-3050 2950);
DISPLAY 0.617021 (-3050 2950);
PAINT SKYBLUE (-3050 2950);
FORCEPROP 1 LAST PART_NUMBER C79254-001
J 0
(-3050 2850);
DISPLAY 0.617021 (-3050 2850);
PAINT BLUE (-3050 2850);
FORCEPROP 2 LAST SEC_TYPE SOT23LF
J 0
(-3050 3150);
DISPLAY 1.021277 (-3050 3150);
PAINT ORANGE (-3050 3150);
DISPLAY INVISIBLE (-3050 3150);
FORCEPROP 0 LAST SEC 1
J 0
(-3050 3100);
DISPLAY 0.680851 (-3050 3100);
PAINT MONO (-3050 3100);
DISPLAY INVISIBLE (-3050 3100);
FORCEPROP 1 LAST PACK_TYPE SOT23LF
J 0
(-3050 2900);
DISPLAY 0.978723 (-3050 2900);
PAINT SKYBLUE (-3050 2900);
DISPLAY INVISIBLE (-3050 2900);
FORCEPROP 1 LAST PATH I51
J 0
(-3050 3100);
DISPLAY 0.978723 (-3050 3100);
PAINT BLUE (-3050 3100);
DISPLAY INVISIBLE (-3050 3100);
FORCEPROP 2 LAST CDS_LIB mstr_discrete
J 0
(-3250 3050);
PAINT MONO (-3250 3050);
DISPLAY INVISIBLE (-3250 3050);
FORCEPROP 0 LAST ROOM HOT_SWAP
J 0
(-3050 3150);
DISPLAY 1.021277 (-3050 3150);
PAINT ORANGE (-3050 3150);
DISPLAY INVISIBLE (-3050 3150);
FORCEADD GND..1
(-3250 2775);
FORCEPROP 3 LASTPIN (-3250 2825) SIG_NAME GND\g
J 0
(-3240 2835);
DISPLAY 0.659574 (-3240 2835);
PAINT MONO (-3240 2835);
DISPLAY INVISIBLE (-3240 2835);
FORCEPROP 1 LAST PATH I52
J 0
(-3175 2775);
DISPLAY 0.872340 (-3175 2775);
PAINT AQUA (-3175 2775);
DISPLAY INVISIBLE (-3175 2775);
FORCEPROP 1 LAST VOLTAGE 0.0V
J 0
(-3295 2732);
DISPLAY 0.340426 (-3295 2732);
PAINT SKYBLUE (-3295 2732);
DISPLAY INVISIBLE (-3295 2732);
FORCEPROP 2 LAST CDS_LIB mstr_symbols
J 0
(-3250 2775);
PAINT MONO (-3250 2775);
DISPLAY INVISIBLE (-3250 2775);
FORCEPROP 1 LAST SIZE 1B
J 0
(-3175 2725);
DISPLAY 2.382979 (-3175 2725);
PAINT GREEN (-3175 2725);
DISPLAY INVISIBLE (-3175 2725);
FORCEPROP 1 LAST BODY_TYPE PLUMBING
J 0
(-3295 2732);
DISPLAY 0.340426 (-3295 2732);
PAINT GREEN (-3295 2732);
DISPLAY INVISIBLE (-3295 2732);
FORCEPROP 1 LAST HDL_POWER GND
J 0
(-3250 2925);
PAINT GREEN (-3250 2925);
DISPLAY INVISIBLE (-3250 2925);
FORCEADD OFFPAGE..1
(-4100 2950);
FORCEPROP 2 LAST $XR2 254 
J 0
(-4382 2914);
DISPLAY 0.638298 (-4382 2914);
PAINT MONO (-4382 2914);
FORCEPROP 2 LAST $XR1 189 
J 0
(-4502 2950);
DISPLAY 0.638298 (-4502 2950);
PAINT MONO (-4502 2950);
FORCEPROP 2 LAST $XR0 148 
J 0
(-4382 2950);
DISPLAY 0.638298 (-4382 2950);
PAINT MONO (-4382 2950);
FORCEPROP 2 LAST PATH I53
J 0
(-4350 3000);
DISPLAY 1.021277 (-4350 3000);
PAINT ORANGE (-4350 3000);
DISPLAY INVISIBLE (-4350 3000);
FORCEPROP 2 LAST CDS_LIB mstr_standard
J 0
(-4100 2950);
PAINT ORANGE (-4100 2950);
DISPLAY INVISIBLE (-4100 2950);
FORCEPROP 1 LAST OFFPAGE TRUE
J 0
(-3775 2825);
DISPLAY 1.404255 (-3775 2825);
PAINT GREEN (-3775 2825);
DISPLAY INVISIBLE (-3775 2825);
FORCEPROP 1 LAST COMMENT_BODY TRUE
J 0
(-3975 2850);
DISPLAY 1.404255 (-3975 2850);
PAINT PEACH (-3975 2850);
DISPLAY INVISIBLE (-3975 2850);
FORCEADD RES..2
(-3550 3500);
FORCEPROP 1 LAST LOCATION R25W185
J 0
(-3505 3625);
DISPLAY 0.617021 (-3505 3625);
PAINT AQUA (-3505 3625);
FORCEPROP 1 LAST TOLERANCE 1%
J 0
(-3505 3525);
DISPLAY 0.617021 (-3505 3525);
PAINT SKYBLUE (-3505 3525);
FORCEPROP 1 LAST VALUE 4.75K
J 0
(-3505 3575);
DISPLAY 0.617021 (-3505 3575);
PAINT SKYBLUE (-3505 3575);
FORCEPROP 1 LASTPIN (-3550 3600) $PN 1
J 0
(-3545 3562);
DISPLAY 0.617021 (-3545 3562);
PAINT ORANGE (-3545 3562);
FORCEPROP 1 LAST WATTAGE 1/16W
J 0
(-3510 3475);
DISPLAY 0.617021 (-3510 3475);
PAINT SKYBLUE (-3510 3475);
FORCEPROP 1 LAST MATERIAL CHIP
J 0
(-3510 3425);
DISPLAY 0.617021 (-3510 3425);
PAINT SKYBLUE (-3510 3425);
FORCEPROP 1 LASTPIN (-3550 3400) $PN 2
J 0
(-3545 3410);
DISPLAY 0.617021 (-3545 3410);
PAINT ORANGE (-3545 3410);
FORCEPROP 1 LAST PACK_TYPE 0402
J 0
(-3510 3325);
DISPLAY 0.617021 (-3510 3325);
PAINT SKYBLUE (-3510 3325);
FORCEPROP 1 LAST PART_NUMBER G21796-072
J 0
(-3510 3375);
DISPLAY 0.617021 (-3510 3375);
PAINT BLUE (-3510 3375);
FORCEPROP 2 LAST CDS_LOCATION R25W185
J 0
(-3505 3625);
DISPLAY 0.617021 (-3505 3625);
PAINT AQUA (-3505 3625);
DISPLAY INVISIBLE (-3505 3625);
FORCEPROP 1 LAST PATH I54
J 0
(-3500 3675);
DISPLAY 0.978723 (-3500 3675);
PAINT WHITE (-3500 3675);
DISPLAY INVISIBLE (-3500 3675);
FORCEPROP 2 LAST SEC 1
J 0
(-3500 3725);
DISPLAY 0.680851 (-3500 3725);
PAINT MONO (-3500 3725);
DISPLAY INVISIBLE (-3500 3725);
FORCEPROP 2 LAST SEC_TYPE 0402
J 0
(-3500 3725);
DISPLAY 1.021277 (-3500 3725);
PAINT ORANGE (-3500 3725);
DISPLAY INVISIBLE (-3500 3725);
FORCEPROP 2 LAST BOM_COST SM_CONTROLLER
J 0
(-3600 3650);
DISPLAY 1.021277 (-3600 3650);
PAINT ORANGE (-3600 3650);
DISPLAY INVISIBLE (-3600 3650);
FORCEPROP 2 LAST CDS_LIB mstr_discrete
J 0
(-3550 3500);
PAINT MONO (-3550 3500);
DISPLAY INVISIBLE (-3550 3500);
FORCEPROP 2 LAST ROOM BMC_MISC
J 0
(-3600 3600);
DISPLAY 1.021277 (-3600 3600);
PAINT ORANGE (-3600 3600);
DISPLAY INVISIBLE (-3600 3600);
FORCEADD P3V3_STBY..1
(-3550 3700);
FORCEPROP 3 LASTPIN (-3550 3650) SIG_NAME P3V3_STBY\g
J 0
(-3540 3660);
DISPLAY 0.659574 (-3540 3660);
PAINT MONO (-3540 3660);
DISPLAY INVISIBLE (-3540 3660);
FORCEPROP 1 LAST PATH I55
J 0
(-3505 3702);
DISPLAY 0.340426 (-3505 3702);
PAINT GREEN (-3505 3702);
DISPLAY INVISIBLE (-3505 3702);
FORCEPROP 1 LAST VOLTAGE 3.3V
J 0
(-3595 3657);
DISPLAY 0.340426 (-3595 3657);
PAINT SKYBLUE (-3595 3657);
DISPLAY INVISIBLE (-3595 3657);
FORCEPROP 2 LAST CDS_LIB mstr_symbols
J 0
(-3550 3700);
PAINT MONO (-3550 3700);
DISPLAY INVISIBLE (-3550 3700);
FORCEPROP 1 LAST SIZE 1B
J 0
(-3505 3722);
DISPLAY 0.340426 (-3505 3722);
PAINT GREEN (-3505 3722);
DISPLAY INVISIBLE (-3505 3722);
FORCEPROP 1 LAST BODY_TYPE PLUMBING
J 0
(-3595 3657);
DISPLAY 0.340426 (-3595 3657);
PAINT GREEN (-3595 3657);
DISPLAY INVISIBLE (-3595 3657);
FORCEPROP 1 LAST HDL_POWER P3V3_STBY
J 0
(-3850 3575);
DISPLAY 0.872340 (-3850 3575);
PAINT ORANGE (-3850 3575);
DISPLAY INVISIBLE (-3850 3575);
FORCEADD TTL1G08..1
(-3400 4200);
FORCEPROP 1 LAST POWER_GROUP VCC=P3V3_STBY;GND=GND;
J 1
(-3375 4025);
DISPLAY 0.617021 (-3375 4025);
PAINT ORANGE (-3375 4025);
FORCEPROP 2 LASTPIN (-3550 4150) $PN 2
J 2
(-3560 4160);
DISPLAY 0.617021 (-3560 4160);
PAINT ORANGE (-3560 4160);
FORCEPROP 2 LASTPIN (-3550 4250) $PN 1
J 2
(-3560 4260);
DISPLAY 0.617021 (-3560 4260);
PAINT ORANGE (-3560 4260);
FORCEPROP 1 LAST PART_NUMBER D10321-001
J 1
(-3425 4300);
DISPLAY 0.617021 (-3425 4300);
PAINT BLUE (-3425 4300);
FORCEPROP 1 LAST VALUE NC7SZ08
J 1
(-3400 4075);
DISPLAY 0.617021 (-3400 4075);
PAINT SKYBLUE (-3400 4075);
FORCEPROP 1 LAST PACK_TYPE SOTLF
J 1
(-3425 4375);
DISPLAY 0.617021 (-3425 4375);
PAINT SKYBLUE (-3425 4375);
FORCEPROP 2 LASTPIN (-3250 4200) $PN 4
J 0
(-3240 4210);
DISPLAY 0.617021 (-3240 4210);
PAINT ORANGE (-3240 4210);
FORCEPROP 1 LAST LOCATION U25W18
J 1
(-3425 4335);
DISPLAY 0.617021 (-3425 4335);
PAINT AQUA (-3425 4335);
FORCEPROP 1 LAST MATERIAL IC
J 1
(-3425 4410);
DISPLAY 0.617021 (-3425 4410);
PAINT SKYBLUE (-3425 4410);
FORCEPROP 2 LAST CDS_LOCATION U25W18
J 1
(-3425 4335);
DISPLAY 0.617021 (-3425 4335);
PAINT AQUA (-3425 4335);
DISPLAY INVISIBLE (-3425 4335);
FORCEPROP 1 LAST PATH I57
J 1
(-3420 4465);
DISPLAY 0.702128 (-3420 4465);
PAINT WHITE (-3420 4465);
DISPLAY INVISIBLE (-3420 4465);
FORCEPROP 0 LAST ROOM CAT_ERR
J 0
(-3425 4500);
DISPLAY 1.021277 (-3425 4500);
PAINT ORANGE (-3425 4500);
DISPLAY INVISIBLE (-3425 4500);
FORCEPROP 2 LAST SEC 1
J 0
(-3400 4500);
DISPLAY 0.680851 (-3400 4500);
PAINT MONO (-3400 4500);
DISPLAY INVISIBLE (-3400 4500);
FORCEPROP 2 LAST SEC_TYPE SOTLF
J 0
(-3400 4500);
DISPLAY 1.021277 (-3400 4500);
PAINT ORANGE (-3400 4500);
DISPLAY INVISIBLE (-3400 4500);
FORCEPROP 2 LAST CDS_LIB mstr_ttl
J 0
(-3400 4200);
PAINT ORANGE (-3400 4200);
DISPLAY INVISIBLE (-3400 4200);
FORCEPROP 0 LAST BOM_COST PROC_SIDEBAND
J 0
(-3425 4600);
DISPLAY 1.021277 (-3425 4600);
PAINT ORANGE (-3425 4600);
DISPLAY INVISIBLE (-3425 4600);
FORCEADD P3V3_STBY..1
(-2700 4000);
FORCEPROP 3 LASTPIN (-2700 3950) SIG_NAME P3V3_STBY\g
J 0
(-2690 3960);
DISPLAY 0.659574 (-2690 3960);
PAINT MONO (-2690 3960);
DISPLAY INVISIBLE (-2690 3960);
FORCEPROP 2 LAST CDS_LIB mstr_symbols
J 0
(-2700 4000);
PAINT ORANGE (-2700 4000);
DISPLAY INVISIBLE (-2700 4000);
FORCEPROP 1 LAST SIZE 1B
J 0
(-2655 4022);
DISPLAY 0.340426 (-2655 4022);
PAINT GREEN (-2655 4022);
DISPLAY INVISIBLE (-2655 4022);
FORCEPROP 1 LAST VOLTAGE 3.3V
J 0
(-2745 3957);
DISPLAY 0.340426 (-2745 3957);
PAINT SKYBLUE (-2745 3957);
DISPLAY INVISIBLE (-2745 3957);
FORCEPROP 1 LAST PATH I58
J 0
(-2655 4002);
DISPLAY 0.340426 (-2655 4002);
PAINT GREEN (-2655 4002);
DISPLAY INVISIBLE (-2655 4002);
FORCEPROP 1 LAST BODY_TYPE PLUMBING
J 0
(-2745 3957);
DISPLAY 0.340426 (-2745 3957);
PAINT GREEN (-2745 3957);
DISPLAY INVISIBLE (-2745 3957);
FORCEPROP 1 LAST HDL_POWER P3V3_STBY
J 0
(-3000 3875);
DISPLAY 0.872340 (-3000 3875);
PAINT ORANGE (-3000 3875);
DISPLAY INVISIBLE (-3000 3875);
FORCEADD GND..1
(-2700 3625);
FORCEPROP 3 LASTPIN (-2700 3675) SIG_NAME GND\g
J 0
(-2690 3685);
DISPLAY 0.659574 (-2690 3685);
PAINT MONO (-2690 3685);
DISPLAY INVISIBLE (-2690 3685);
FORCEPROP 1 LAST PATH I59
J 0
(-2625 3625);
DISPLAY 0.872340 (-2625 3625);
PAINT AQUA (-2625 3625);
DISPLAY INVISIBLE (-2625 3625);
FORCEPROP 1 LAST HDL_POWER GND
J 0
(-2700 3775);
DISPLAY 0.872340 (-2700 3775);
PAINT GREEN (-2700 3775);
DISPLAY INVISIBLE (-2700 3775);
FORCEPROP 1 LAST BODY_TYPE PLUMBING
J 0
(-2745 3582);
DISPLAY 0.340426 (-2745 3582);
PAINT GREEN (-2745 3582);
DISPLAY INVISIBLE (-2745 3582);
FORCEPROP 2 LAST CDS_LIB mstr_symbols
J 0
(-2700 3625);
PAINT ORANGE (-2700 3625);
DISPLAY INVISIBLE (-2700 3625);
FORCEPROP 1 LAST SIZE 1B
J 0
(-2625 3575);
DISPLAY 0.872340 (-2625 3575);
PAINT AQUA (-2625 3575);
DISPLAY INVISIBLE (-2625 3575);
FORCEPROP 1 LAST VOLTAGE 0.0V
J 0
(-2745 3582);
DISPLAY 0.340426 (-2745 3582);
PAINT SKYBLUE (-2745 3582);
DISPLAY INVISIBLE (-2745 3582);
FORCEADD P3V3_STBY..1
(-6700 3550);
FORCEPROP 3 LASTPIN (-6700 3500) SIG_NAME P3V3_STBY\g
J 0
(-6690 3510);
DISPLAY 0.659574 (-6690 3510);
PAINT MONO (-6690 3510);
DISPLAY INVISIBLE (-6690 3510);
FORCEPROP 1 LAST PATH I6
J 0
(-6655 3552);
DISPLAY 0.340426 (-6655 3552);
PAINT GREEN (-6655 3552);
DISPLAY INVISIBLE (-6655 3552);
FORCEPROP 2 LAST CDS_LIB mstr_symbols
J 0
(-6700 3550);
PAINT ORANGE (-6700 3550);
DISPLAY INVISIBLE (-6700 3550);
FORCEPROP 1 LAST SIZE 1B
J 0
(-6655 3572);
DISPLAY 0.340426 (-6655 3572);
PAINT GREEN (-6655 3572);
DISPLAY INVISIBLE (-6655 3572);
FORCEPROP 1 LAST VOLTAGE 3.3V
J 0
(-6745 3507);
DISPLAY 0.340426 (-6745 3507);
PAINT SKYBLUE (-6745 3507);
DISPLAY INVISIBLE (-6745 3507);
FORCEPROP 1 LAST BODY_TYPE PLUMBING
J 0
(-6745 3507);
DISPLAY 0.340426 (-6745 3507);
PAINT GREEN (-6745 3507);
DISPLAY INVISIBLE (-6745 3507);
FORCEPROP 1 LAST HDL_POWER P3V3_STBY
J 0
(-7000 3425);
DISPLAY 0.872340 (-7000 3425);
PAINT ORANGE (-7000 3425);
DISPLAY INVISIBLE (-7000 3425);
FORCEADD CAP_A..1
(-2700 3800);
FORCEPROP 1 LAST MATERIAL X7R
J 0
(-2650 3700);
DISPLAY 0.617021 (-2650 3700);
PAINT SKYBLUE (-2650 3700);
FORCEPROP 1 LAST VALUE 0.1UF
J 0
(-2650 3850);
DISPLAY 0.617021 (-2650 3850);
PAINT SKYBLUE (-2650 3850);
FORCEPROP 1 LASTPIN (-2700 3900) $PN 1
J 0
(-2690 3880);
DISPLAY 0.617021 (-2690 3880);
PAINT ORANGE (-2690 3880);
FORCEPROP 1 LASTPIN (-2700 3700) $PN 2
J 0
(-2690 3680);
DISPLAY 0.617021 (-2690 3680);
PAINT ORANGE (-2690 3680);
FORCEPROP 1 LAST LOCATION C25W100
J 0
(-2650 3900);
DISPLAY 0.617021 (-2650 3900);
PAINT AQUA (-2650 3900);
FORCEPROP 1 LAST TOLERANCE 10%
J 0
(-2650 3750);
DISPLAY 0.617021 (-2650 3750);
PAINT SKYBLUE (-2650 3750);
FORCEPROP 1 LAST VOLTAGE 16V
J 0
(-2650 3800);
DISPLAY 0.617021 (-2650 3800);
PAINT SKYBLUE (-2650 3800);
FORCEPROP 1 LAST PACK_TYPE 0402V
J 0
(-2650 3600);
DISPLAY 0.617021 (-2650 3600);
PAINT SKYBLUE (-2650 3600);
FORCEPROP 1 LAST PART_NUMBER A36096-030
J 0
(-2650 3650);
DISPLAY 0.617021 (-2650 3650);
PAINT BLUE (-2650 3650);
FORCEPROP 2 LAST CDS_LOCATION C25W100
J 0
(-2650 3900);
DISPLAY 0.617021 (-2650 3900);
PAINT AQUA (-2650 3900);
DISPLAY INVISIBLE (-2650 3900);
FORCEPROP 2 LAST ROOM PROC_SIDEBAND
J 0
(-2650 3950);
DISPLAY 1.021277 (-2650 3950);
PAINT ORANGE (-2650 3950);
DISPLAY INVISIBLE (-2650 3950);
FORCEPROP 2 LAST BOM_COST PROC_SIDEBAND
J 0
(-2650 4000);
DISPLAY 1.021277 (-2650 4000);
PAINT ORANGE (-2650 4000);
DISPLAY INVISIBLE (-2650 4000);
FORCEPROP 2 LAST CDS_LIB dev_discrete
J 0
(-2700 3800);
PAINT ORANGE (-2700 3800);
DISPLAY INVISIBLE (-2700 3800);
FORCEPROP 2 LAST CDS_SEC 1
J 0
(-2650 3950);
PAINT ORANGE (-2650 3950);
DISPLAY INVISIBLE (-2650 3950);
FORCEPROP 2 LAST SEC_TYPE 0402V
J 0
(-2650 4000);
DISPLAY 1.021277 (-2650 4000);
PAINT ORANGE (-2650 4000);
DISPLAY INVISIBLE (-2650 4000);
FORCEPROP 2 LAST SEC 1
J 0
(-2650 4000);
DISPLAY 0.680851 (-2650 4000);
PAINT MONO (-2650 4000);
DISPLAY INVISIBLE (-2650 4000);
FORCEPROP 1 LAST PATH I60
J 0
(-2650 3950);
DISPLAY 0.978723 (-2650 3950);
PAINT WHITE (-2650 3950);
DISPLAY INVISIBLE (-2650 3950);
FORCEADD OFFPAGE..1
(-4200 4250);
FORCEPROP 2 LAST $XR2 255 
J 0
(-4452 4286);
DISPLAY 0.638298 (-4452 4286);
PAINT MONO (-4452 4286);
FORCEPROP 2 LAST $XR1 146 
J 0
(-4452 4214);
DISPLAY 0.638298 (-4452 4214);
PAINT MONO (-4452 4214);
FORCEPROP 2 LAST $XR0 111 
J 0
(-4452 4250);
DISPLAY 0.638298 (-4452 4250);
PAINT MONO (-4452 4250);
FORCEPROP 2 LAST CDS_LIB mstr_standard
J 0
(-4200 4250);
PAINT ORANGE (-4200 4250);
DISPLAY INVISIBLE (-4200 4250);
FORCEPROP 2 LAST PATH I61
J 0
(-4475 4300);
DISPLAY 1.021277 (-4475 4300);
PAINT ORANGE (-4475 4300);
DISPLAY INVISIBLE (-4475 4300);
FORCEPROP 1 LAST OFFPAGE TRUE
J 0
(-3875 4125);
DISPLAY 1.404255 (-3875 4125);
PAINT GREEN (-3875 4125);
DISPLAY INVISIBLE (-3875 4125);
FORCEPROP 1 LAST COMMENT_BODY TRUE
J 0
(-4075 4150);
DISPLAY 1.404255 (-4075 4150);
PAINT PEACH (-4075 4150);
DISPLAY INVISIBLE (-4075 4150);
FORCEADD OFFPAGE..2
(-2700 4200);
FORCEPROP 2 LAST $XR0 254 
J 0
(-2511 4200);
DISPLAY 0.638298 (-2511 4200);
PAINT MONO (-2511 4200);
FORCEPROP 2 LAST PATH I62
J 0
(-2500 4250);
DISPLAY 1.021277 (-2500 4250);
PAINT ORANGE (-2500 4250);
DISPLAY INVISIBLE (-2500 4250);
FORCEPROP 2 LAST ROOM CPU_XDP_DEBUG
J 0
(-2500 4250);
DISPLAY 1.617021 (-2500 4250);
PAINT WHITE (-2500 4250);
DISPLAY INVISIBLE (-2500 4250);
FORCEPROP 2 LAST BOM_COST DEBUG
J 0
(-2500 4250);
DISPLAY 1.617021 (-2500 4250);
PAINT WHITE (-2500 4250);
DISPLAY INVISIBLE (-2500 4250);
FORCEPROP 2 LAST CDS_LIB mstr_standard
J 0
(-2700 4200);
DISPLAY 2.212766 (-2700 4200);
PAINT ORANGE (-2700 4200);
DISPLAY INVISIBLE (-2700 4200);
FORCEPROP 1 LAST OFFPAGE TRUE
J 0
(-2375 4075);
PAINT GREEN (-2375 4075);
DISPLAY INVISIBLE (-2375 4075);
FORCEPROP 1 LAST COMMENT_BODY TRUE
J 0
(-2745 4105);
DISPLAY 1.893617 (-2745 4105);
PAINT PEACH (-2745 4105);
DISPLAY INVISIBLE (-2745 4105);
FORCEADD SW-SLIDE75-GP..1
R 2
(-2050 3325);
FORCEPROP 2 LASTPIN (-1900 3400) $PN NP1
J 0
(-1890 3410);
DISPLAY 0.808511 (-1890 3410);
PAINT ORANGE (-1890 3410);
FORCEPROP 2 LASTPIN (-2100 3000) $PN 6
R 1
J 2
(-2115 3040);
DISPLAY 0.808511 (-2115 3040);
PAINT ORANGE (-2115 3040);
FORCEPROP 2 LASTPIN (-2000 3000) $PN 7
R 1
J 2
(-2015 3040);
DISPLAY 0.808511 (-2015 3040);
PAINT ORANGE (-2015 3040);
FORCEPROP 2 LASTPIN (-2300 3250) $PN 3
J 2
(-2310 3260);
DISPLAY 0.808511 (-2310 3260);
PAINT ORANGE (-2310 3260);
FORCEPROP 2 LASTPIN (-2100 3650) $PN 4
R 1
J 0
(-2115 3660);
DISPLAY 0.808511 (-2115 3660);
PAINT ORANGE (-2115 3660);
FORCEPROP 2 LASTPIN (-2000 3650) $PN 5
R 1
J 0
(-2015 3660);
DISPLAY 0.808511 (-2015 3660);
PAINT ORANGE (-2015 3660);
FORCEPROP 2 LASTPIN (-2300 3400) $PN 1
J 2
(-2310 3410);
DISPLAY 0.808511 (-2310 3410);
PAINT ORANGE (-2310 3410);
FORCEPROP 2 LASTPIN (-2300 3300) $PN 2
J 2
(-2310 3310);
DISPLAY 0.808511 (-2310 3310);
PAINT ORANGE (-2310 3310);
FORCEPROP 1 LAST LOCATION S9W1
J 0
(-2225 3525);
DISPLAY 0.617021 (-2225 3525);
PAINT GREEN (-2225 3525);
FORCEPROP 2 LASTPIN (-1900 3250) $PN NP2
J 0
(-1890 3260);
DISPLAY 0.808511 (-1890 3260);
PAINT ORANGE (-1890 3260);
FORCEPROP 1 LAST VALUE SW-SLIDE75-GP
J 0
(-1925 3125);
DISPLAY 0.617021 (-1925 3125);
PAINT GREEN (-1925 3125);
FORCEPROP 2 LAST CDS_LIB w_hdl
J 2
(-2050 3325);
DISPLAY INVISIBLE (-2050 3325);
FORCEPROP 1 LAST CDS_LMAN_SYM_OUTLINE -100,175,100,-175
J 2
(-2050 3325);
DISPLAY 0.468085 (-2050 3325);
PAINT GREEN (-2050 3325);
DISPLAY INVISIBLE (-2050 3325);
FORCEPROP 1 LAST PATH I63
J 0
(-2050 3809);
DISPLAY 0.617021 (-2050 3809);
PAINT GREEN (-2050 3809);
DISPLAY INVISIBLE (-2050 3809);
FORCEPROP 1 LAST PART_NUMBER 62.40018.461
J 0
(-2050 2844);
DISPLAY 0.617021 (-2050 2844);
PAINT GREEN (-2050 2844);
DISPLAY INVISIBLE (-2050 2844);
FORCEPROP 2 LAST SEC_TYPE DISCRET-G6
J 0
(-2050 3850);
DISPLAY 1.021277 (-2050 3850);
PAINT ORANGE (-2050 3850);
DISPLAY INVISIBLE (-2050 3850);
FORCEPROP 2 LAST SEC 1
J 0
(-2050 3850);
DISPLAY 0.680851 (-2050 3850);
PAINT MONO (-2050 3850);
DISPLAY INVISIBLE (-2050 3850);
FORCEPROP 1 LAST PACK_TYPE DISCRET-G6
J 0
(-2050 3325);
DISPLAY 0.617021 (-2050 3325);
PAINT GREEN (-2050 3325);
DISPLAY INVISIBLE (-2050 3325);
FORCEADD GND..1
(-2300 3175);
FORCEPROP 3 LASTPIN (-2300 3225) SIG_NAME GND\g
J 0
(-2290 3235);
DISPLAY 0.659574 (-2290 3235);
PAINT MONO (-2290 3235);
DISPLAY INVISIBLE (-2290 3235);
FORCEPROP 1 LAST PATH I64
J 0
(-2225 3175);
DISPLAY 0.872340 (-2225 3175);
PAINT AQUA (-2225 3175);
DISPLAY INVISIBLE (-2225 3175);
FORCEPROP 1 LAST HDL_POWER GND
J 0
(-2300 3325);
DISPLAY 0.872340 (-2300 3325);
PAINT GREEN (-2300 3325);
DISPLAY INVISIBLE (-2300 3325);
FORCEPROP 1 LAST BODY_TYPE PLUMBING
J 0
(-2345 3132);
DISPLAY 0.340426 (-2345 3132);
PAINT GREEN (-2345 3132);
DISPLAY INVISIBLE (-2345 3132);
FORCEPROP 2 LAST CDS_LIB mstr_symbols
J 0
(-2300 3175);
PAINT ORANGE (-2300 3175);
DISPLAY INVISIBLE (-2300 3175);
FORCEPROP 1 LAST SIZE 1B
J 0
(-2225 3125);
DISPLAY 0.872340 (-2225 3125);
PAINT AQUA (-2225 3125);
DISPLAY INVISIBLE (-2225 3125);
FORCEPROP 1 LAST VOLTAGE 0.0V
J 0
(-2345 3132);
DISPLAY 0.340426 (-2345 3132);
PAINT SKYBLUE (-2345 3132);
DISPLAY INVISIBLE (-2345 3132);
FORCEADD GND..1
(-2100 2875);
FORCEPROP 3 LASTPIN (-2100 2925) SIG_NAME GND\g
J 0
(-2090 2935);
DISPLAY 0.659574 (-2090 2935);
PAINT MONO (-2090 2935);
DISPLAY INVISIBLE (-2090 2935);
FORCEPROP 1 LAST PATH I65
J 0
(-2025 2875);
DISPLAY 0.872340 (-2025 2875);
PAINT AQUA (-2025 2875);
DISPLAY INVISIBLE (-2025 2875);
FORCEPROP 1 LAST VOLTAGE 0.0V
J 0
(-2145 2832);
DISPLAY 0.340426 (-2145 2832);
PAINT SKYBLUE (-2145 2832);
DISPLAY INVISIBLE (-2145 2832);
FORCEPROP 1 LAST SIZE 1B
J 0
(-2025 2825);
DISPLAY 0.872340 (-2025 2825);
PAINT AQUA (-2025 2825);
DISPLAY INVISIBLE (-2025 2825);
FORCEPROP 2 LAST CDS_LIB mstr_symbols
J 0
(-2100 2875);
PAINT ORANGE (-2100 2875);
DISPLAY INVISIBLE (-2100 2875);
FORCEPROP 1 LAST BODY_TYPE PLUMBING
J 0
(-2145 2832);
DISPLAY 0.340426 (-2145 2832);
PAINT GREEN (-2145 2832);
DISPLAY INVISIBLE (-2145 2832);
FORCEPROP 1 LAST HDL_POWER GND
J 0
(-2100 3025);
DISPLAY 0.872340 (-2100 3025);
PAINT GREEN (-2100 3025);
DISPLAY INVISIBLE (-2100 3025);
FORCEADD RES..1
(-6000 5300);
FORCEPROP 1 LAST PART_NUMBER G21497-005
J 0
(-5900 5350);
DISPLAY 0.617021 (-5900 5350);
PAINT BLUE (-5900 5350);
FORCEPROP 1 LAST WATTAGE 1/16W
J 0
(-5825 5250);
DISPLAY 0.510638 (-5825 5250);
PAINT SKYBLUE (-5825 5250);
FORCEPROP 1 LAST PACK_TYPE 0402
J 0
(-5925 5250);
DISPLAY 0.617021 (-5925 5250);
PAINT SKYBLUE (-5925 5250);
FORCEPROP 1 LAST TOLERANCE 5%
J 0
(-6025 5250);
DISPLAY 0.617021 (-6025 5250);
PAINT SKYBLUE (-6025 5250);
FORCEPROP 1 LAST VALUE 0.0
J 0
(-6100 5250);
DISPLAY 0.617021 (-6100 5250);
PAINT SKYBLUE (-6100 5250);
FORCEPROP 1 LASTPIN (-6100 5300) $PN 1
J 0
(-6088 5312);
DISPLAY 0.617021 (-6088 5312);
PAINT WHITE (-6088 5312);
FORCEPROP 1 LASTPIN (-5900 5300) $PN 2
J 0
(-5938 5312);
DISPLAY 0.617021 (-5938 5312);
PAINT WHITE (-5938 5312);
FORCEPROP 1 LAST LOCATION R25W187
J 0
(-6100 5350);
DISPLAY 0.617021 (-6100 5350);
PAINT AQUA (-6100 5350);
FORCEPROP 1 LAST PATH I66
J 0
(-6050 5450);
DISPLAY 0.978723 (-6050 5450);
PAINT WHITE (-6050 5450);
DISPLAY INVISIBLE (-6050 5450);
FORCEPROP 2 LAST CDS_LIB mstr_discrete
J 0
(-6000 5300);
DISPLAY 1.340426 (-6000 5300);
PAINT ORANGE (-6000 5300);
DISPLAY INVISIBLE (-6000 5300);
FORCEPROP 2 LAST BOM_COST PROC_SIDEBAND
J 0
(-6000 5300);
PAINT MONO (-6000 5300);
DISPLAY INVISIBLE (-6000 5300);
FORCEPROP 1 LAST MATERIAL CHIP
J 0
(-5850 5200);
DISPLAY 0.510638 (-5850 5200);
PAINT SKYBLUE (-5850 5200);
DISPLAY INVISIBLE (-5850 5200);
FORCEPROP 2 LAST ROOM CPU0
J 0
(-6050 5450);
PAINT PEACH (-6050 5450);
DISPLAY INVISIBLE (-6050 5450);
FORCEPROP 2 LAST SEC_TYPE 0402
J 0
(-6050 5525);
DISPLAY 1.021277 (-6050 5525);
PAINT ORANGE (-6050 5525);
DISPLAY INVISIBLE (-6050 5525);
FORCEPROP 2 LAST SEC 1
J 0
(-6050 5525);
DISPLAY 0.680851 (-6050 5525);
PAINT MONO (-6050 5525);
DISPLAY INVISIBLE (-6050 5525);
FORCEPROP 2 LAST CDS_LOCATION R25W187
J 0
(-6475 5300);
DISPLAY 0.617021 (-6475 5300);
PAINT AQUA (-6475 5300);
DISPLAY INVISIBLE (-6475 5300);
FORCEADD OFFPAGE..2
(-5250 5300);
FORCEPROP 2 LAST $XR0 255 
J 0
(-5061 5300);
DISPLAY 0.638298 (-5061 5300);
PAINT MONO (-5061 5300);
FORCEPROP 2 LAST PATH I67
J 0
(-5050 5350);
DISPLAY 1.021277 (-5050 5350);
PAINT ORANGE (-5050 5350);
DISPLAY INVISIBLE (-5050 5350);
FORCEPROP 2 LAST ROOM CPU_XDP_DEBUG
J 0
(-5050 5350);
DISPLAY 1.617021 (-5050 5350);
PAINT WHITE (-5050 5350);
DISPLAY INVISIBLE (-5050 5350);
FORCEPROP 2 LAST BOM_COST DEBUG
J 0
(-5050 5350);
DISPLAY 1.617021 (-5050 5350);
PAINT WHITE (-5050 5350);
DISPLAY INVISIBLE (-5050 5350);
FORCEPROP 2 LAST CDS_LIB mstr_standard
J 0
(-5250 5300);
DISPLAY 2.212766 (-5250 5300);
PAINT ORANGE (-5250 5300);
DISPLAY INVISIBLE (-5250 5300);
FORCEPROP 1 LAST OFFPAGE TRUE
J 0
(-4925 5175);
PAINT GREEN (-4925 5175);
DISPLAY INVISIBLE (-4925 5175);
FORCEPROP 1 LAST COMMENT_BODY TRUE
J 0
(-5295 5205);
DISPLAY 1.893617 (-5295 5205);
PAINT PEACH (-5295 5205);
DISPLAY INVISIBLE (-5295 5205);
FORCEADD RES..2
(-7100 4150);
FORCEPROP 1 LAST WATTAGE 1/16W
J 0
(-7060 4150);
DISPLAY 0.617021 (-7060 4150);
PAINT SKYBLUE (-7060 4150);
FORCEPROP 1 LAST LOCATION R25W179
J 0
(-7055 4300);
DISPLAY 0.617021 (-7055 4300);
PAINT AQUA (-7055 4300);
FORCEPROP 1 LASTPIN (-7100 4250) $PN 1
J 0
(-7095 4212);
DISPLAY 0.617021 (-7095 4212);
PAINT WHITE (-7095 4212);
FORCEPROP 1 LASTPIN (-7100 4050) $PN 2
J 0
(-7095 4060);
DISPLAY 0.617021 (-7095 4060);
PAINT WHITE (-7095 4060);
FORCEPROP 1 LAST PACK_TYPE 0402
J 0
(-7060 4000);
DISPLAY 0.617021 (-7060 4000);
PAINT SKYBLUE (-7060 4000);
FORCEPROP 1 LAST PART_NUMBER G21796-026
J 0
(-7060 4050);
DISPLAY 0.617021 (-7060 4050);
PAINT BLUE (-7060 4050);
FORCEPROP 1 LAST MATERIAL CHIP
J 0
(-7060 4100);
DISPLAY 0.617021 (-7060 4100);
PAINT SKYBLUE (-7060 4100);
FORCEPROP 1 LAST TOLERANCE 1%
J 0
(-7055 4200);
DISPLAY 0.617021 (-7055 4200);
PAINT SKYBLUE (-7055 4200);
FORCEPROP 1 LAST VALUE 1.00K
J 0
(-7055 4250);
DISPLAY 0.617021 (-7055 4250);
PAINT SKYBLUE (-7055 4250);
FORCEPROP 1 LAST PATH I7
J 0
(-7050 4325);
DISPLAY 0.978723 (-7050 4325);
PAINT WHITE (-7050 4325);
DISPLAY INVISIBLE (-7050 4325);
FORCEPROP 2 LAST CDS_LOCATION R25W179
J 0
(-7055 4275);
DISPLAY 0.617021 (-7055 4275);
PAINT AQUA (-7055 4275);
DISPLAY INVISIBLE (-7055 4275);
FORCEPROP 2 LAST ROOM PROC_RSTS_PGOODS
J 0
(-7075 3925);
DISPLAY 1.617021 (-7075 3925);
PAINT WHITE (-7075 3925);
DISPLAY INVISIBLE (-7075 3925);
FORCEPROP 2 LAST $SEC 1
J 0
(-7050 4375);
DISPLAY 1.510638 (-7050 4375);
PAINT MONO (-7050 4375);
DISPLAY INVISIBLE (-7050 4375);
FORCEPROP 2 LAST CDS_SEC 1
J 0
(-7050 4375);
DISPLAY 2.276596 (-7050 4375);
PAINT ORANGE (-7050 4375);
DISPLAY INVISIBLE (-7050 4375);
FORCEPROP 2 LAST CDS_LIB mstr_discrete
J 0
(-7100 4150);
DISPLAY 1.617021 (-7100 4150);
PAINT ORANGE (-7100 4150);
DISPLAY INVISIBLE (-7100 4150);
FORCEPROP 2 LAST BOM_COST PROC_SIDEBAND
J 0
(-7100 4150);
DISPLAY 1.617021 (-7100 4150);
PAINT WHITE (-7100 4150);
DISPLAY INVISIBLE (-7100 4150);
FORCEADD P3V3_STBY..1
(-7100 4350);
FORCEPROP 3 LASTPIN (-7100 4300) SIG_NAME P3V3_STBY\g
J 0
(-7090 4310);
DISPLAY 0.659574 (-7090 4310);
PAINT MONO (-7090 4310);
DISPLAY INVISIBLE (-7090 4310);
FORCEPROP 1 LAST PATH I8
J 0
(-7055 4352);
DISPLAY 0.340426 (-7055 4352);
PAINT GREEN (-7055 4352);
DISPLAY INVISIBLE (-7055 4352);
FORCEPROP 2 LAST CDS_LIB mstr_symbols
J 0
(-7100 4350);
PAINT ORANGE (-7100 4350);
DISPLAY INVISIBLE (-7100 4350);
FORCEPROP 1 LAST SIZE 1B
J 0
(-7055 4372);
DISPLAY 0.340426 (-7055 4372);
PAINT GREEN (-7055 4372);
DISPLAY INVISIBLE (-7055 4372);
FORCEPROP 1 LAST VOLTAGE 3.3V
J 0
(-7145 4307);
DISPLAY 0.340426 (-7145 4307);
PAINT SKYBLUE (-7145 4307);
DISPLAY INVISIBLE (-7145 4307);
FORCEPROP 1 LAST BODY_TYPE PLUMBING
J 0
(-7145 4307);
DISPLAY 0.340426 (-7145 4307);
PAINT GREEN (-7145 4307);
DISPLAY INVISIBLE (-7145 4307);
FORCEPROP 1 LAST HDL_POWER P3V3_STBY
J 0
(-7400 4225);
DISPLAY 0.872340 (-7400 4225);
PAINT ORANGE (-7400 4225);
DISPLAY INVISIBLE (-7400 4225);
FORCEADD CAP_A..1
(-6700 4150);
FORCEPROP 1 LAST LOCATION C25W96
J 0
(-6650 4300);
DISPLAY 0.617021 (-6650 4300);
PAINT AQUA (-6650 4300);
FORCEPROP 1 LAST VALUE 0.1UF
J 0
(-6650 4250);
DISPLAY 0.617021 (-6650 4250);
PAINT SKYBLUE (-6650 4250);
FORCEPROP 1 LASTPIN (-6700 4050) $PN 2
J 0
(-6690 4030);
DISPLAY 0.617021 (-6690 4030);
PAINT ORANGE (-6690 4030);
FORCEPROP 1 LASTPIN (-6700 4250) $PN 1
J 0
(-6690 4230);
DISPLAY 0.617021 (-6690 4230);
PAINT ORANGE (-6690 4230);
FORCEPROP 1 LAST VOLTAGE 16V
J 0
(-6650 4200);
DISPLAY 0.617021 (-6650 4200);
PAINT SKYBLUE (-6650 4200);
FORCEPROP 1 LAST TOLERANCE 10%
J 0
(-6650 4150);
DISPLAY 0.617021 (-6650 4150);
PAINT SKYBLUE (-6650 4150);
FORCEPROP 1 LAST PACK_TYPE 0402V
J 0
(-6650 4000);
DISPLAY 0.617021 (-6650 4000);
PAINT SKYBLUE (-6650 4000);
FORCEPROP 1 LAST PART_NUMBER A36096-030
J 0
(-6650 4050);
DISPLAY 0.617021 (-6650 4050);
PAINT BLUE (-6650 4050);
FORCEPROP 1 LAST MATERIAL X7R
J 0
(-6650 4100);
DISPLAY 0.617021 (-6650 4100);
PAINT SKYBLUE (-6650 4100);
FORCEPROP 1 LAST PATH I9
J 0
(-6650 4300);
DISPLAY 0.978723 (-6650 4300);
PAINT WHITE (-6650 4300);
DISPLAY INVISIBLE (-6650 4300);
FORCEPROP 2 LAST CDS_LOCATION C25W96
J 0
(-6650 4250);
DISPLAY 0.617021 (-6650 4250);
PAINT AQUA (-6650 4250);
DISPLAY INVISIBLE (-6650 4250);
FORCEPROP 2 LAST CDS_LIB dev_discrete
J 0
(-6700 4150);
PAINT ORANGE (-6700 4150);
DISPLAY INVISIBLE (-6700 4150);
FORCEPROP 2 LAST CDS_SEC 1
J 0
(-6650 4300);
PAINT ORANGE (-6650 4300);
DISPLAY INVISIBLE (-6650 4300);
FORCEPROP 2 LAST SEC 1
J 0
(-6650 4350);
DISPLAY 0.680851 (-6650 4350);
PAINT MONO (-6650 4350);
DISPLAY INVISIBLE (-6650 4350);
FORCEPROP 2 LAST SEC_TYPE 0402V
J 0
(-6650 4350);
DISPLAY 1.021277 (-6650 4350);
PAINT ORANGE (-6650 4350);
DISPLAY INVISIBLE (-6650 4350);
FORCEPROP 0 LAST BOM_COST SM_THERM
J 0
(-6650 4450);
DISPLAY 1.021277 (-6650 4450);
PAINT ORANGE (-6650 4450);
DISPLAY INVISIBLE (-6650 4450);
FORCEPROP 0 LAST ROOM CPU_FANS
J 0
(-6650 4350);
DISPLAY 1.021277 (-6650 4350);
PAINT ORANGE (-6650 4350);
DISPLAY INVISIBLE (-6650 4350);
FORCEADD CAD_NOTE..1
(-2250 4000);
FORCEPROP 0 LAST L2 U25E18
J 0
(-2400 3800);
DISPLAY 1.021277 (-2400 3800);
PAINT ORANGE (-2400 3800);
FORCEPROP 0 LAST L1 PLACE CAP CLOSE TO
J 0
(-2400 3850);
DISPLAY 1.021277 (-2400 3850);
PAINT ORANGE (-2400 3850);
FORCEPROP 2 LAST CDS_LIB mstr_symbols
J 0
(-2250 4000);
PAINT ORANGE (-2250 4000);
DISPLAY INVISIBLE (-2250 4000);
FORCEPROP 1 LAST COMMENT_BODY TRUE
J 0
(-2225 4100);
DISPLAY 0.978723 (-2225 4100);
PAINT ORANGE (-2225 4100);
DISPLAY INVISIBLE (-2225 4100);
FORCEADD CAD_NOTE..1
(-6300 3550);
FORCEPROP 0 LAST L1 PLACE CAP CLOSE
J 0
(-6450 3425);
DISPLAY 0.617021 (-6450 3425);
PAINT WHITE (-6450 3425);
FORCEPROP 0 LAST L2 TO IC
J 0
(-6450 3350);
DISPLAY 0.617021 (-6450 3350);
PAINT WHITE (-6450 3350);
FORCEPROP 2 LAST CDS_LIB mstr_symbols
J 0
(-6300 3550);
PAINT ORANGE (-6300 3550);
DISPLAY INVISIBLE (-6300 3550);
FORCEPROP 1 LAST COMMENT_BODY TRUE
J 0
(-6275 3650);
DISPLAY 1.361702 (-6275 3650);
PAINT WHITE (-6275 3650);
DISPLAY INVISIBLE (-6275 3650);
FORCEADD CAD_NOTE..1
(-6300 4350);
FORCEPROP 0 LAST L1 PLACE CAP CLOSE
J 0
(-6450 4225);
DISPLAY 0.617021 (-6450 4225);
PAINT WHITE (-6450 4225);
FORCEPROP 0 LAST L2 TO IC
J 0
(-6450 4150);
DISPLAY 0.617021 (-6450 4150);
PAINT WHITE (-6450 4150);
FORCEPROP 2 LAST CDS_LIB mstr_symbols
J 0
(-6300 4350);
PAINT ORANGE (-6300 4350);
DISPLAY INVISIBLE (-6300 4350);
FORCEPROP 1 LAST COMMENT_BODY TRUE
J 0
(-6275 4450);
DISPLAY 1.361702 (-6275 4450);
PAINT WHITE (-6275 4450);
DISPLAY INVISIBLE (-6275 4450);
FORCEADD INTEL_CORP_BPAGE..1
(-1250 1850);
FORCEPROP 1 LAST CDS_CON_LAST_MODIFIED Fri Jun 16 17:49:33 2017
J 0
(-2675 2175);
PAINT ORANGE (-2675 2175);
DISPLAY INVISIBLE (-2675 2175);
FORCEPROP 1 LAST CUSTOM_TXT_CDS <CON_LAST_MODIFIED>
J 0
(-5250 1950);
PAINT ORANGE (-5250 1950);
FORCEPROP 2 LAST CUSTOM_TXT_CDS <XR_PAGE_TITLE>
J 0
(-9140 7100);
DISPLAY 0.638298 (-9140 7100);
PAINT PINK (-9140 7100);
DISPLAY INVISIBLE (-9140 7100);
FORCEPROP 2 LAST CUSTOM_TXT_CDS Tue Sep 20 14:39:26 2016
J 0
(-5250 1950);
PAINT ORANGE (-5250 1950);
FORCEPROP 2 LAST CUSTOM_TXT_CDS <CURRENT_DESIGN_SHEET> OF <TOTAL_DESIGN_SHEETS>
J 0
(-1750 1875);
PAINT ORANGE (-1750 1875);
FORCEPROP 1 LAST SCH_TITLE BMC REMOTE DEBUG CIRCUIT - 2 OF 2
J 0
(-9200 1900);
DISPLAY 2.468085 (-9200 1900);
PAINT ORANGE (-9200 1900);
FORCEPROP 2 LAST CDS_LIB mstr_symbols
J 0
(-1250 1850);
PAINT MONO (-1250 1850);
DISPLAY INVISIBLE (-1250 1850);
FORCEPROP 2 LAST PAGE_BORDER TRUE
J 0
(-9140 7100);
DISPLAY 0.638298 (-9140 7100);
PAINT PINK (-9140 7100);
DISPLAY INVISIBLE (-9140 7100);
FORCEPROP 1 LAST COMMENT_BODY TRUE
J 0
(-1238 1862);
DISPLAY 0.468085 (-1238 1862);
PAINT GREEN (-1238 1862);
DISPLAY INVISIBLE (-1238 1862);
FORCEPROP 2 LAST CDS_XR_PAGE_TITLE CR-255 : @BASEBOARD_FAB2_LIB.BASEBOARD_FAB2(SCH_1):PAGE255
J 0
(-9140 7100);
DISPLAY 0.638298 (-9140 7100);
PAINT PINK (-9140 7100);
DISPLAY INVISIBLE (-9140 7100);
WIRE 16 -1 (-6700 4050)(-6700 4025);
WIRE 16 -1 (-6700 4300)(-6700 4250);
WIRE 16 -1 (-8450 4850)(-8450 4825);
WIRE 16 -1 (-8150 4850)(-8150 4825);
WIRE 16 -1 (-7750 4900)(-7750 4875);
WIRE 16 -1 (-7750 4950)(-7750 4900);
WIRE 16 -1 (-7750 4900)(-7650 4900);
WIRE 16 -1 (-7750 5000)(-7750 4950);
WIRE 16 -1 (-7750 4950)(-7650 4950);
WIRE 16 -1 (-7750 5000)(-7650 5000);
WIRE 16 -1 (-6550 5675)(-6550 5700);
WIRE 16 -1 (-6550 6000)(-6550 5950);
WIRE 16 -1 (-6550 5950)(-6650 5950);
WIRE 16 -1 (-6550 5900)(-6550 5950);
WIRE 16 -1 (-6650 5950)(-6650 5600);
WIRE 16 -1 (-6650 5600)(-6750 5600);
WIRE 16 -1 (-5750 5650)(-5750 5625);
WIRE 16 -1 (-6050 5650)(-5750 5650);
WIRE 16 -1 (-5750 5750)(-5750 5650);
WIRE 16 -1 (-6050 5750)(-6050 5650);
WIRE 16 -1 (-7100 3500)(-7100 3450);
WIRE 16 -1 (-5750 6400)(-5750 6350);
WIRE 16 -1 (-5300 5450)(-5300 5425);
WIRE 16 -1 (-5900 5450)(-5300 5450);
WIRE 16 -1 (-5150 6400)(-5150 6350);
WIRE 16 -1 (-2250 4550)(-2250 4500);
WIRE 16 -1 (-2250 4300)(-2250 4275);
WIRE 16 -1 (-6700 3250)(-6700 3225);
WIRE 16 -1 (-3250 2850)(-3250 2825);
WIRE 16 -1 (-3550 3650)(-3550 3600);
WIRE 16 -1 (-2700 3950)(-2700 3900);
WIRE 16 -1 (-2700 3700)(-2700 3675);
WIRE 16 -1 (-6700 3500)(-6700 3450);
WIRE 16 -1 (-2300 3250)(-2300 3225);
WIRE 16 -1 (-2100 2950)(-2100 2925);
WIRE 16 -1 (-2100 2950)(-2000 2950);
WIRE 16 -1 (-2100 3000)(-2100 2950);
WIRE 16 -1 (-1650 2950)(-2000 2950);
WIRE 16 -1 (-2000 3000)(-2000 2950);
WIRE 16 -1 (-1650 2950)(-1650 3700);
WIRE 16 -1 (-1650 3700)(-2000 3700);
WIRE 16 -1 (-2000 3700)(-2100 3700);
WIRE 16 -1 (-2000 3700)(-2000 3650);
WIRE 16 -1 (-2100 3700)(-2100 3650);
WIRE 16 -1 (-7100 4300)(-7100 4250);
WIRE 16 -1 (-3550 4250)(-4150 4250);
FORCEPROP 2 LAST SIG_NAME XDP_PRESENT_N
J 0
(-4085 4260);
DISPLAY 0.638298 (-4085 4260);
PAINT ORANGE (-4085 4260);
WIRE 3 682 (-9100 6650)(-9100 2750);
WIRE 3 682 (-4600 6650)(-9100 6650);
WIRE 3 682 (-9100 2750)(-4600 2750);
WIRE 3 682 (-4600 2750)(-4600 6650);
WIRE 16 -1 (-6150 5550)(-6750 5550);
WIRE 16 -1 (-6150 6050)(-6150 5550);
WIRE 16 -1 (-5150 6050)(-5150 6100);
WIRE 16 -1 (-6050 6050)(-6150 6050);
WIRE 16 -1 (-6050 5950)(-6050 6050);
WIRE 16 -1 (-5750 6050)(-6050 6050);
FORCEPROP 0 LAST VOLTAGE +0.7 V
J 0
(-5875 6125);
DISPLAY 1.404255 (-5875 6125);
PAINT SKYBLUE (-5875 6125);
DISPLAY INVISIBLE (-5875 6125);
FORCEPROP 2 LAST SIG_NAME P0V7_GTL2014_VREF_6
J 0
(-6610 5560);
DISPLAY 0.617021 (-6610 5560);
PAINT ORANGE (-6610 5560);
FORCEPROP 2 LASTPROP $XRERR UNIQUE?
J 0
(-6850 5560);
DISPLAY 0.638298 (-6850 5560);
PAINT MONO (-6850 5560);
DISPLAY INVISIBLE (-6850 5560);
WIRE 16 -1 (-5750 6050)(-5750 5950);
WIRE 16 -1 (-5750 6050)(-5150 6050);
WIRE 16 -1 (-5750 6150)(-5750 6050);
WIRE 16 -1 (-8450 5250)(-8450 5050);
WIRE 16 -1 (-7650 5250)(-8450 5250);
FORCEPROP 2 LAST SIG_NAME PD_GTL2014_6_B2
J 0
(-8385 5260);
DISPLAY 0.638298 (-8385 5260);
PAINT ORANGE (-8385 5260);
FORCEPROP 2 LASTPROP $XRERR UNIQUE?
J 0
(-8625 5260);
DISPLAY 0.638298 (-8625 5260);
PAINT MONO (-8625 5260);
DISPLAY INVISIBLE (-8625 5260);
WIRE 16 -1 (-6750 5200)(-6100 5200);
FORCEPROP 2 LAST SIG_NAME BMC_PRDY_N
J 0
(-6660 5210);
DISPLAY 0.638298 (-6660 5210);
PAINT ORANGE (-6660 5210);
WIRE 3 682 (-1550 2650)(-4550 2650);
WIRE 3 682 (-1550 5700)(-1550 2650);
WIRE 3 682 (-4550 5700)(-4550 2650);
WIRE 3 682 (-4550 5700)(-1550 5700);
WIRE 3 682 (-6050 5250)(-6050 5100);
WIRE 16 -1 (-6750 5250)(-6200 5250);
FORCEPROP 2 LAST SIG_NAME TP_GTL2014_6_A2
J 0
(-6660 5260);
DISPLAY 0.638298 (-6660 5260);
PAINT ORANGE (-6660 5260);
FORCEPROP 2 LASTPROP $XRERR UNIQUE?
J 0
(-6170 5250);
DISPLAY 0.638298 (-6170 5250);
PAINT MONO (-6170 5250);
DISPLAY INVISIBLE (-6170 5250);
WIRE 16 -1 (-3450 2950)(-4050 2950);
FORCEPROP 2 LAST SIG_NAME BMC_JTAG_SEL_N
J 0
(-3985 2960);
DISPLAY 0.638298 (-3985 2960);
PAINT ORANGE (-3985 2960);
WIRE 16 -1 (-6750 5450)(-6100 5450);
FORCEPROP 2 LAST SIG_NAME PD_GTL2014_DIR_6
J 0
(-6612 5473);
DISPLAY 0.617021 (-6612 5473);
PAINT ORANGE (-6612 5473);
FORCEPROP 2 LASTPROP $XRERR UNIQUE?
J 0
(-6852 5473);
DISPLAY 0.638298 (-6852 5473);
PAINT MONO (-6852 5473);
DISPLAY INVISIBLE (-6852 5473);
WIRE 16 -1 (-5900 5300)(-5300 5300);
FORCEPROP 2 LAST SIG_NAME JTAG_BMC_BUF_TDO
J 0
(-5835 5310);
DISPLAY 0.638298 (-5835 5310);
PAINT ORANGE (-5835 5310);
WIRE 16 -1 (-6750 5300)(-6100 5300);
FORCEPROP 2 LAST SIG_NAME JTAG_BMC_BUF_TDO_R
J 0
(-6660 5310);
DISPLAY 0.638298 (-6660 5310);
PAINT ORANGE (-6660 5310);
FORCEPROP 2 LASTPROP $XRERR UNIQUE?
J 0
(-6900 5310);
DISPLAY 0.638298 (-6900 5310);
PAINT MONO (-6900 5310);
DISPLAY INVISIBLE (-6900 5310);
WIRE 16 -1 (-6750 5150)(-6200 5150);
FORCEPROP 2 LAST SIG_NAME TP_GTL2014_6_A0
J 0
(-6660 5160);
DISPLAY 0.638298 (-6660 5160);
PAINT ORANGE (-6660 5160);
FORCEPROP 2 LASTPROP $XRERR UNIQUE?
J 0
(-6170 5150);
DISPLAY 0.638298 (-6170 5150);
PAINT MONO (-6170 5150);
DISPLAY INVISIBLE (-6170 5150);
WIRE 3 682 (-5400 6550)(-5400 6000);
WIRE 3 682 (-4750 6550)(-5400 6550);
WIRE 3 682 (-5400 6000)(-4750 6000);
WIRE 3 682 (-4750 6000)(-4750 6550);
WIRE 16 -1 (-6150 3100)(-5500 3100);
WIRE 16 -1 (-5500 3900)(-5500 3100);
WIRE 16 -1 (-5500 3900)(-5450 3900);
WIRE 16 -1 (-6150 3900)(-5500 3900);
FORCEPROP 2 LAST SIG_NAME CPU_XDP_PRESENT_N
J 0
(-6035 3910);
DISPLAY 0.638298 (-6035 3910);
PAINT ORANGE (-6035 3910);
WIRE 16 -1 (-3550 4150)(-3750 4150);
WIRE 16 -1 (-3750 4150)(-3750 3850);
WIRE 16 -1 (-3750 3850)(-3150 3850);
WIRE 16 -1 (-3150 3850)(-3150 3300);
WIRE 16 -1 (-2300 3300)(-3150 3300);
WIRE 16 -1 (-3250 3300)(-3250 3250);
WIRE 16 -1 (-3150 3300)(-3250 3300);
WIRE 16 -1 (-3550 3400)(-3550 3300);
WIRE 16 -1 (-3550 3300)(-3250 3300);
FORCEPROP 2 LAST SIG_NAME BMC_JTAG_SEL
J 0
(-3585 3860);
DISPLAY 0.638298 (-3585 3860);
PAINT ORANGE (-3585 3860);
FORCEPROP 2 LASTPROP $XRERR UNIQUE?
J 0
(-3825 3860);
DISPLAY 0.638298 (-3825 3860);
PAINT MONO (-3825 3860);
DISPLAY INVISIBLE (-3825 3860);
WIRE 3 682 (-4200 5450)(-4200 5200);
WIRE 3 682 (-3150 5450)(-4200 5450);
WIRE 3 682 (-4200 5200)(-3150 5200);
WIRE 3 682 (-3150 5200)(-3150 5450);
WIRE 3 682 (-2400 3750)(-2400 2700);
WIRE 3 682 (-1600 3750)(-2400 3750);
WIRE 3 682 (-2400 2700)(-1600 2700);
WIRE 3 682 (-1600 2700)(-1600 3750);
WIRE 16 -1 (-3100 4950)(-3700 4950);
FORCEPROP 2 LAST SIG_NAME JTAG_BMC_TMS
J 0
(-3644 4974);
DISPLAY 0.638298 (-3644 4974);
PAINT ORANGE (-3644 4974);
WIRE 16 -1 (-3100 4750)(-3700 4750);
FORCEPROP 2 LAST SIG_NAME JTAG_BMC_TDI
J 0
(-3650 4757);
DISPLAY 0.638298 (-3650 4757);
PAINT ORANGE (-3650 4757);
WIRE 16 -1 (-3200 4200)(-3250 4200);
WIRE 16 -1 (-3200 4200)(-2750 4200);
WIRE 16 -1 (-3200 4650)(-3200 4200);
FORCEPROP 2 LAST SIG_NAME BMC_JTAG_SEL_BUF
J 0
(-3160 4210);
DISPLAY 0.638298 (-3160 4210);
PAINT ORANGE (-3160 4210);
WIRE 16 -1 (-3100 4650)(-3200 4650);
WIRE 16 -1 (-3100 4850)(-3200 4850);
WIRE 16 -1 (-3200 4850)(-3200 4650);
WIRE 16 -1 (-3200 5050)(-3200 4850);
WIRE 16 -1 (-3100 5050)(-3200 5050);
WIRE 16 -1 (-3200 5250)(-3200 5050);
WIRE 16 -1 (-3100 5250)(-3200 5250);
WIRE 16 -1 (-7100 3250)(-7100 3100);
WIRE 16 -1 (-7100 3100)(-6400 3100);
WIRE 16 -1 (-8150 3100)(-7100 3100);
FORCEPROP 2 LAST SIG_NAME BMC_DEBUG_EN_N
J 0
(-7635 3110);
DISPLAY 0.638298 (-7635 3110);
PAINT ORANGE (-7635 3110);
WIRE 16 -1 (-7850 5550)(-8400 5550);
FORCEPROP 2 LAST SIG_NAME XDP_PRDY_N
J 0
(-8335 5560);
DISPLAY 0.638298 (-8335 5560);
PAINT ORANGE (-8335 5560);
WIRE 16 -1 (-7850 5200)(-7850 5550);
WIRE 16 -1 (-7650 5200)(-7850 5200);
WIRE 16 -1 (-7750 5300)(-7650 5300);
WIRE 16 -1 (-7750 5650)(-7750 5300);
WIRE 16 -1 (-8400 5650)(-7750 5650);
FORCEPROP 2 LAST SIG_NAME XDP_TDO
J 0
(-8335 5660);
DISPLAY 0.638298 (-8335 5660);
PAINT ORANGE (-8335 5660);
WIRE 16 -1 (-8150 5150)(-8150 5050);
WIRE 16 -1 (-7650 5150)(-8150 5150);
FORCEPROP 2 LAST SIG_NAME PD_GTL2014_6_B0
J 0
(-8135 5160);
DISPLAY 0.638298 (-8135 5160);
PAINT ORANGE (-8135 5160);
FORCEPROP 2 LASTPROP $XRERR UNIQUE?
J 0
(-8375 5160);
DISPLAY 0.638298 (-8375 5160);
PAINT MONO (-8375 5160);
DISPLAY INVISIBLE (-8375 5160);
WIRE 16 -1 (-7100 4050)(-7100 3900);
WIRE 16 -1 (-6400 3900)(-7100 3900);
WIRE 16 -1 (-8150 3900)(-7100 3900);
FORCEPROP 2 LAST SIG_NAME XDP_PRESENT_N
J 0
(-7635 3910);
DISPLAY 0.638298 (-7635 3910);
PAINT ORANGE (-7635 3910);
WIRE 16 -1 (-2700 4950)(-2100 4950);
FORCEPROP 2 LAST SIG_NAME JTAG_BMC_BUF_TMS
J 0
(-2578 4958);
DISPLAY 0.638298 (-2578 4958);
PAINT ORANGE (-2578 4958);
WIRE 16 -1 (-2700 5150)(-2100 5150);
FORCEPROP 2 LAST SIG_NAME JTAG_BMC_BUF_TDO
J 0
(-2585 5160);
DISPLAY 0.638298 (-2585 5160);
PAINT ORANGE (-2585 5160);
WIRE 16 -1 (-2700 5350)(-2100 5350);
FORCEPROP 2 LAST SIG_NAME BMC_PWR_DEBUG_BUF_N
J 0
(-2594 5360);
DISPLAY 0.638298 (-2594 5360);
PAINT ORANGE (-2594 5360);
WIRE 3 682 (-1750 5450)(-2650 5450);
WIRE 3 682 (-1750 5250)(-1750 5450);
WIRE 3 682 (-2650 5450)(-2650 5250);
WIRE 3 682 (-2650 5250)(-1750 5250);
WIRE 16 -1 (-3100 5350)(-3700 5350);
FORCEPROP 2 LAST SIG_NAME BMC_PWR_DEBUG_N
J 0
(-3644 5360);
DISPLAY 0.638298 (-3644 5360);
PAINT ORANGE (-3644 5360);
WIRE 16 -1 (-3700 5150)(-3100 5150);
FORCEPROP 2 LAST SIG_NAME JTAG_BMC_TDO
J 0
(-3635 5160);
DISPLAY 0.638298 (-3635 5160);
PAINT ORANGE (-3635 5160);
WIRE 16 -1 (-2700 4750)(-2100 4750);
FORCEPROP 2 LAST SIG_NAME JTAG_BMC_BUF_TDI
J 0
(-2592 4775);
DISPLAY 0.638298 (-2592 4775);
PAINT ORANGE (-2592 4775);
DOT 1 (-2100 2950);
DOT 1 (-3200 4200);
DOT 1 (-3150 3300);
DOT 1 (-2000 3700);
DOT 1 (-3250 3300);
DOT 1 (-3200 4850);
DOT 1 (-5750 5650);
DOT 1 (-7100 3100);
DOT 1 (-7100 3900);
DOT 1 (-7750 4900);
DOT 1 (-7750 4950);
DOT 1 (-6550 5950);
DOT 1 (-5500 3900);
DOT 1 (-6050 6050);
DOT 1 (-5750 6050);
DOT 1 (-3200 4650);
DOT 1 (-3200 5050);
DOT 1 (-2000 2950);
FORCENOTE
PLACE R25W187 NEAR U25W11
(-6075 5000) 0;
DISPLAY LEFT (-6075 5000);
DISPLAY 1.021277 (-6075 5000);
PAINT PURPLE (-6075 5000);
FORCENOTE
TP FAB3-DVT ADD 0OHM RES R25W187 20161205
(-6100 5050) 0;
DISPLAY LEFT (-6100 5050);
DISPLAY 0.638298 (-6100 5050);
PAINT RED (-6100 5050);
FORCENOTE
TP FAB3 RECONNECT 1014
(-5300 5150) 0;
DISPLAY LEFT (-5300 5150);
DISPLAY 0.638298 (-5300 5150);
PAINT RED (-5300 5150);
FORCENOTE
TP FAB3 ADD RES 0922
(-5400 5950) 0;
DISPLAY LEFT (-5400 5950);
DISPLAY 0.638298 (-5400 5950);
PAINT RED (-5400 5950);
FORCENOTE
WILL ADD A SWITCH 62.40018.461 (DIPTRONICS/MSS3-V-T/R).
(-2675 2525) 0;
DISPLAY LEFT (-2675 2525);
DISPLAY 0.638298 (-2675 2525);
PAINT PURPLE (-2675 2525);
FORCENOTE
TP FAB3 ADD BMC REMOTE CIRCUIT 0920
(-9100 2700) 0;
DISPLAY LEFT (-9100 2700);
DISPLAY 1.021277 (-9100 2700);
PAINT RED (-9100 2700);
FORCENOTE
TP FAB3 ADD CIRCUIT 1014
(-4550 2575) 0;
DISPLAY LEFT (-4550 2575);
DISPLAY 0.638298 (-4550 2575);
PAINT RED (-4550 2575);
FORCENOTE
TP FAB3 NOPOP R25W164 0922
(-6450 6125) 0;
DISPLAY LEFT (-6450 6125);
DISPLAY 0.638298 (-6450 6125);
PAINT RED (-6450 6125);
FORCENOTE
TP FAB3 CHANGE CONNECTION 1024
(-4200 5475) 0;
DISPLAY LEFT (-4200 5475);
DISPLAY 0.638298 (-4200 5475);
PAINT RED (-4200 5475);
FORCENOTE
TP FAB3 CHANGE CONNECTION 1024
(-2650 5475) 0;
DISPLAY LEFT (-2650 5475);
DISPLAY 0.638298 (-2650 5475);
PAINT RED (-2650 5475);
FORCENOTE
TP FAB3 ADD C25W100 AND U25W18 1021
(-3000 4100) 0;
DISPLAY LEFT (-3000 4100);
DISPLAY 0.638298 (-3000 4100);
PAINT RED (-3000 4100);
FORCENOTE
1-2: ENABLE BMC DEBUG
(-2350 2800) 0;
DISPLAY LEFT (-2350 2800);
DISPLAY 0.638298 (-2350 2800);
PAINT PURPLE (-2350 2800);
FORCENOTE
2-3: DISABLE BMC DEBUG (DEFAULT)
(-2350 2750) 0;
DISPLAY LEFT (-2350 2750);
DISPLAY 0.638298 (-2350 2750);
PAINT PURPLE (-2350 2750);
FORCENOTE
TP FAB3-DVT ADD SWITCH S9W1 20161116
(-2400 2675) 0;
DISPLAY LEFT (-2400 2675);
DISPLAY 0.638298 (-2400 2675);
PAINT RED (-2400 2675);
QUIT
